FILE_TYPE = MACRO_DRAWING;
SET COLOR_WIRE YELLOW;
SET COLOR_PROP MONO;
SET COLOR_DOT WHITE;
SET COLOR_ARC YELLOW;
SET COLOR_BODY GREEN;
SET COLOR_NOTE MONO;
SET PROP_DISPLAY VALUE;
SET PAGE_NUMBER P243;
FORCEADD GND..1
(-7100 875);
FORCEPROP 3 LASTPIN (-7100 925) SIG_NAME GND\g
J 0
(-7090 935);
DISPLAY 0.659574 (-7090 935);
PAINT MONO (-7090 935);
DISPLAY INVISIBLE (-7090 935);
FORCEPROP 2 LAST CDS_LIB mstr_symbols
J 0
(-7100 875);
PAINT MONO (-7100 875);
DISPLAY INVISIBLE (-7100 875);
FORCEPROP 1 LAST SIZE 1B
J 0
(-7025 825);
DISPLAY 1.723404 (-7025 825);
PAINT GREEN (-7025 825);
DISPLAY INVISIBLE (-7025 825);
FORCEPROP 2 LAST BOM_COST PROC_VRD_VCCIN_CPU0
J 0
(-7475 950);
DISPLAY 1.446809 (-7475 950);
PAINT MONO (-7475 950);
DISPLAY INVISIBLE (-7475 950);
FORCEPROP 2 LAST ROOM VDDQ_ABC_PWR_VR
J 0
(-7650 950);
DISPLAY 1.936170 (-7650 950);
PAINT ORANGE (-7650 950);
DISPLAY INVISIBLE (-7650 950);
FORCEPROP 1 LAST VOLTAGE 0
J 0
(-7100 875);
PAINT SKYBLUE (-7100 875);
DISPLAY INVISIBLE (-7100 875);
FORCEPROP 1 LAST PATH I1
J 0
(-7025 875);
DISPLAY 0.872340 (-7025 875);
PAINT AQUA (-7025 875);
DISPLAY INVISIBLE (-7025 875);
FORCEPROP 1 LAST BODY_TYPE PLUMBING
J 0
(-7145 832);
DISPLAY 0.340426 (-7145 832);
PAINT GREEN (-7145 832);
DISPLAY INVISIBLE (-7145 832);
FORCEPROP 1 LAST HDL_POWER GND
J 0
(-7100 1025);
DISPLAY 1.723404 (-7100 1025);
PAINT GREEN (-7100 1025);
DISPLAY INVISIBLE (-7100 1025);
FORCEADD GND..1
(-7125 3125);
FORCEPROP 3 LASTPIN (-7125 3175) SIG_NAME GND\g
J 0
(-7115 3185);
DISPLAY 0.659574 (-7115 3185);
PAINT MONO (-7115 3185);
DISPLAY INVISIBLE (-7115 3185);
FORCEPROP 2 LAST CDS_LIB mstr_symbols
J 0
(-7125 3125);
PAINT MONO (-7125 3125);
DISPLAY INVISIBLE (-7125 3125);
FORCEPROP 1 LAST SIZE 1B
J 0
(-7050 3075);
DISPLAY 1.723404 (-7050 3075);
PAINT GREEN (-7050 3075);
DISPLAY INVISIBLE (-7050 3075);
FORCEPROP 2 LAST BOM_COST PROC_VRD_VCCIN_CPU0
J 0
(-7500 3200);
DISPLAY 1.446809 (-7500 3200);
PAINT MONO (-7500 3200);
DISPLAY INVISIBLE (-7500 3200);
FORCEPROP 2 LAST ROOM VDDQ_ABC_PWR_VR
J 0
(-7675 3200);
DISPLAY 1.936170 (-7675 3200);
PAINT ORANGE (-7675 3200);
DISPLAY INVISIBLE (-7675 3200);
FORCEPROP 1 LAST VOLTAGE 0
J 0
(-7125 3125);
PAINT SKYBLUE (-7125 3125);
DISPLAY INVISIBLE (-7125 3125);
FORCEPROP 1 LAST PATH I11
J 0
(-7050 3125);
DISPLAY 0.872340 (-7050 3125);
PAINT AQUA (-7050 3125);
DISPLAY INVISIBLE (-7050 3125);
FORCEPROP 1 LAST BODY_TYPE PLUMBING
J 0
(-7170 3082);
DISPLAY 0.340426 (-7170 3082);
PAINT GREEN (-7170 3082);
DISPLAY INVISIBLE (-7170 3082);
FORCEPROP 1 LAST HDL_POWER GND
J 0
(-7125 3275);
DISPLAY 1.723404 (-7125 3275);
PAINT GREEN (-7125 3275);
DISPLAY INVISIBLE (-7125 3275);
FORCEADD CAP..1
(-7125 3650);
FORCEPROP 1 LAST VALUE 100UF
J 0
(-7075 3700);
DISPLAY 0.617021 (-7075 3700);
PAINT SKYBLUE (-7075 3700);
FORCEPROP 1 LAST LOCATION C5G117
J 0
(-7075 3750);
DISPLAY 0.617021 (-7075 3750);
PAINT AQUA (-7075 3750);
FORCEPROP 1 LAST MATERIAL X5R
J 0
(-7075 3550);
DISPLAY 0.617021 (-7075 3550);
PAINT SKYBLUE (-7075 3550);
FORCEPROP 1 LAST PACK_TYPE 0805
J 0
(-7075 3450);
DISPLAY 0.617021 (-7075 3450);
PAINT SKYBLUE (-7075 3450);
FORCEPROP 1 LAST PART_NUMBER 602433-112
J 0
(-7075 3500);
DISPLAY 0.617021 (-7075 3500);
PAINT BLUE (-7075 3500);
FORCEPROP 1 LAST TOLERANCE 20%
J 0
(-7075 3600);
DISPLAY 0.617021 (-7075 3600);
PAINT SKYBLUE (-7075 3600);
FORCEPROP 1 LAST VOLTAGE 4V
J 0
(-7075 3650);
DISPLAY 0.617021 (-7075 3650);
PAINT SKYBLUE (-7075 3650);
FORCEPROP 0 LAST SIDE_SKU 1S
J 0
(-7225 3725);
DISPLAY 1.021277 (-7225 3725);
PAINT ORANGE (-7225 3725);
FORCEPROP 1 LASTPIN (-7125 3750) $PN 1
J 0
(-7115 3730);
DISPLAY 0.787234 (-7115 3730);
PAINT ORANGE (-7115 3730);
DISPLAY INVISIBLE (-7115 3730);
FORCEPROP 1 LASTPIN (-7125 3550) $PN 2
J 0
(-7115 3530);
DISPLAY 0.787234 (-7115 3530);
PAINT ORANGE (-7115 3530);
DISPLAY INVISIBLE (-7115 3530);
FORCEPROP 2 LAST CDS_LIB mstr_discrete
J 0
(-7125 3650);
PAINT MONO (-7125 3650);
DISPLAY INVISIBLE (-7125 3650);
FORCEPROP 2 LAST ROOM VDDQ_KLM_PWR_VR
J 0
(-7075 3800);
PAINT MONO (-7075 3800);
DISPLAY INVISIBLE (-7075 3800);
FORCEPROP 2 LAST BOM_COST MEM_VRD_PVDDQ_CD
J 0
(-7075 3800);
PAINT MONO (-7075 3800);
DISPLAY INVISIBLE (-7075 3800);
FORCEPROP 0 LAST CDS_LOCATION C5G117
J 0
(-7075 3800);
PAINT MONO (-7075 3800);
DISPLAY INVISIBLE (-7075 3800);
FORCEPROP 0 LAST $SEC 1
J 0
(-7075 3800);
PAINT MONO (-7075 3800);
DISPLAY INVISIBLE (-7075 3800);
FORCEPROP 0 LAST CDS_SEC 1
J 0
(-7075 3800);
PAINT MONO (-7075 3800);
DISPLAY INVISIBLE (-7075 3800);
FORCEPROP 1 LAST PATH I12
J 0
(-7075 3800);
DISPLAY 0.978723 (-7075 3800);
PAINT WHITE (-7075 3800);
DISPLAY INVISIBLE (-7075 3800);
FORCEADD CAP..1
(-6700 3650);
FORCEPROP 1 LAST VOLTAGE 4V
J 0
(-6650 3650);
DISPLAY 0.617021 (-6650 3650);
PAINT SKYBLUE (-6650 3650);
FORCEPROP 1 LAST TOLERANCE 20%
J 0
(-6650 3600);
DISPLAY 0.617021 (-6650 3600);
PAINT SKYBLUE (-6650 3600);
FORCEPROP 1 LAST MATERIAL X5R
J 0
(-6650 3550);
DISPLAY 0.617021 (-6650 3550);
PAINT SKYBLUE (-6650 3550);
FORCEPROP 1 LAST PART_NUMBER 602433-112
J 0
(-6650 3500);
DISPLAY 0.617021 (-6650 3500);
PAINT BLUE (-6650 3500);
FORCEPROP 1 LAST PACK_TYPE 0805
J 0
(-6650 3450);
DISPLAY 0.617021 (-6650 3450);
PAINT SKYBLUE (-6650 3450);
FORCEPROP 1 LAST VALUE 100UF
J 0
(-6650 3700);
DISPLAY 0.617021 (-6650 3700);
PAINT SKYBLUE (-6650 3700);
FORCEPROP 1 LAST LOCATION C5G118
J 0
(-6650 3750);
DISPLAY 0.617021 (-6650 3750);
PAINT AQUA (-6650 3750);
FORCEPROP 0 LAST SIDE_SKU 1S
J 0
(-6800 3725);
DISPLAY 1.021277 (-6800 3725);
PAINT ORANGE (-6800 3725);
FORCEPROP 1 LASTPIN (-6700 3750) $PN 1
J 0
(-6690 3730);
DISPLAY 0.787234 (-6690 3730);
PAINT ORANGE (-6690 3730);
DISPLAY INVISIBLE (-6690 3730);
FORCEPROP 1 LASTPIN (-6700 3550) $PN 2
J 0
(-6690 3530);
DISPLAY 0.787234 (-6690 3530);
PAINT ORANGE (-6690 3530);
DISPLAY INVISIBLE (-6690 3530);
FORCEPROP 2 LAST CDS_LIB mstr_discrete
J 0
(-6700 3650);
PAINT MONO (-6700 3650);
DISPLAY INVISIBLE (-6700 3650);
FORCEPROP 2 LAST BOM_COST MEM_VRD_PVDDQ_CD
J 0
(-6650 3800);
PAINT MONO (-6650 3800);
DISPLAY INVISIBLE (-6650 3800);
FORCEPROP 2 LAST ROOM VDDQ_KLM_PWR_VR
J 0
(-6650 3800);
PAINT MONO (-6650 3800);
DISPLAY INVISIBLE (-6650 3800);
FORCEPROP 0 LAST CDS_LOCATION C5G118
J 0
(-6650 3800);
PAINT MONO (-6650 3800);
DISPLAY INVISIBLE (-6650 3800);
FORCEPROP 0 LAST $SEC 1
J 0
(-6650 3800);
PAINT MONO (-6650 3800);
DISPLAY INVISIBLE (-6650 3800);
FORCEPROP 0 LAST CDS_SEC 1
J 0
(-6650 3800);
PAINT MONO (-6650 3800);
DISPLAY INVISIBLE (-6650 3800);
FORCEPROP 1 LAST PATH I13
J 0
(-6650 3800);
DISPLAY 0.978723 (-6650 3800);
PAINT WHITE (-6650 3800);
DISPLAY INVISIBLE (-6650 3800);
FORCEADD PVDDQ_GHJ..1
(-7125 4075);
FORCEPROP 3 LASTPIN (-7125 4025) SIG_NAME PVDDQ_GHJ\g
J 0
(-7115 4035);
DISPLAY 0.659574 (-7115 4035);
PAINT MONO (-7115 4035);
DISPLAY INVISIBLE (-7115 4035);
FORCEPROP 2 LAST CDS_LIB mstr_symbols
J 0
(-7125 4075);
PAINT MONO (-7125 4075);
DISPLAY INVISIBLE (-7125 4075);
FORCEPROP 1 LAST VOLTAGE 1.2V
J 0
(-7170 4032);
DISPLAY 0.340426 (-7170 4032);
PAINT SKYBLUE (-7170 4032);
DISPLAY INVISIBLE (-7170 4032);
FORCEPROP 1 LAST PATH I26
J 0
(-7075 4100);
DISPLAY 0.872340 (-7075 4100);
PAINT AQUA (-7075 4100);
DISPLAY INVISIBLE (-7075 4100);
FORCEPROP 1 LAST BODY_TYPE PLUMBING
J 0
(-7170 4032);
DISPLAY 0.340426 (-7170 4032);
PAINT GREEN (-7170 4032);
DISPLAY INVISIBLE (-7170 4032);
FORCEPROP 1 LAST HDL_POWER PVDDQ_GHJ
J 1
(-7125 4125);
DISPLAY 0.872340 (-7125 4125);
PAINT GREEN (-7125 4125);
DISPLAY INVISIBLE (-7125 4125);
FORCEADD GND..1
(-3600 975);
FORCEPROP 3 LASTPIN (-3600 1025) SIG_NAME GND\g
J 0
(-3590 1035);
DISPLAY 0.659574 (-3590 1035);
PAINT MONO (-3590 1035);
DISPLAY INVISIBLE (-3590 1035);
FORCEPROP 2 LAST CDS_LIB mstr_symbols
J 0
(-3600 975);
PAINT MONO (-3600 975);
DISPLAY INVISIBLE (-3600 975);
FORCEPROP 1 LAST VOLTAGE 0
J 0
(-3600 975);
PAINT SKYBLUE (-3600 975);
DISPLAY INVISIBLE (-3600 975);
FORCEPROP 2 LAST ROOM VDDQ_ABC_PWR_VR
J 0
(-4150 1050);
DISPLAY 1.936170 (-4150 1050);
PAINT ORANGE (-4150 1050);
DISPLAY INVISIBLE (-4150 1050);
FORCEPROP 2 LAST BOM_COST PROC_VRD_VCCIN_CPU0
J 0
(-3975 1050);
DISPLAY 1.446809 (-3975 1050);
PAINT MONO (-3975 1050);
DISPLAY INVISIBLE (-3975 1050);
FORCEPROP 1 LAST SIZE 1B
J 0
(-3525 925);
DISPLAY 1.723404 (-3525 925);
PAINT GREEN (-3525 925);
DISPLAY INVISIBLE (-3525 925);
FORCEPROP 1 LAST PATH I27
J 0
(-3525 975);
DISPLAY 0.872340 (-3525 975);
PAINT AQUA (-3525 975);
DISPLAY INVISIBLE (-3525 975);
FORCEPROP 1 LAST BODY_TYPE PLUMBING
J 0
(-3645 932);
DISPLAY 0.340426 (-3645 932);
PAINT GREEN (-3645 932);
DISPLAY INVISIBLE (-3645 932);
FORCEPROP 1 LAST HDL_POWER GND
J 0
(-3600 1125);
DISPLAY 1.723404 (-3600 1125);
PAINT GREEN (-3600 1125);
DISPLAY INVISIBLE (-3600 1125);
FORCEADD PVDDQ_KLM..1
(-3600 1800);
FORCEPROP 3 LASTPIN (-3600 1750) SIG_NAME PVDDQ_KLM\g
J 0
(-3590 1760);
DISPLAY 0.659574 (-3590 1760);
PAINT MONO (-3590 1760);
DISPLAY INVISIBLE (-3590 1760);
FORCEPROP 2 LAST CDS_LIB mstr_symbols
J 0
(-3600 1800);
PAINT MONO (-3600 1800);
DISPLAY INVISIBLE (-3600 1800);
FORCEPROP 2 LAST BOM_COST VDDQ_KLM_PWR_VR
J 0
(-3600 1900);
DISPLAY 1.446809 (-3600 1900);
PAINT MONO (-3600 1900);
DISPLAY INVISIBLE (-3600 1900);
FORCEPROP 2 LAST ROOM VDDQ_KLM_PWR_VR
J 0
(-3600 1900);
DISPLAY 1.936170 (-3600 1900);
PAINT ORANGE (-3600 1900);
DISPLAY INVISIBLE (-3600 1900);
FORCEPROP 1 LAST VOLTAGE 1.2V
J 0
(-3645 1757);
DISPLAY 0.340426 (-3645 1757);
PAINT SKYBLUE (-3645 1757);
DISPLAY INVISIBLE (-3645 1757);
FORCEPROP 1 LAST PATH I29
J 0
(-3550 1825);
DISPLAY 0.872340 (-3550 1825);
PAINT AQUA (-3550 1825);
DISPLAY INVISIBLE (-3550 1825);
FORCEPROP 1 LAST BODY_TYPE PLUMBING
J 0
(-3645 1757);
DISPLAY 0.340426 (-3645 1757);
PAINT GREEN (-3645 1757);
DISPLAY INVISIBLE (-3645 1757);
FORCEPROP 1 LAST HDL_POWER PVDDQ_KLM
J 1
(-3600 1850);
DISPLAY 0.872340 (-3600 1850);
PAINT GREEN (-3600 1850);
DISPLAY INVISIBLE (-3600 1850);
FORCEADD PVDDQ_GHJ..1
(-7100 1700);
FORCEPROP 3 LASTPIN (-7100 1650) SIG_NAME PVDDQ_GHJ\g
J 0
(-7090 1660);
DISPLAY 0.659574 (-7090 1660);
PAINT MONO (-7090 1660);
DISPLAY INVISIBLE (-7090 1660);
FORCEPROP 2 LAST CDS_LIB mstr_symbols
J 0
(-7100 1700);
PAINT MONO (-7100 1700);
DISPLAY INVISIBLE (-7100 1700);
FORCEPROP 1 LAST VOLTAGE 1.2V
J 0
(-7145 1657);
DISPLAY 0.340426 (-7145 1657);
PAINT SKYBLUE (-7145 1657);
DISPLAY INVISIBLE (-7145 1657);
FORCEPROP 1 LAST PATH I3
J 0
(-7050 1725);
DISPLAY 0.872340 (-7050 1725);
PAINT AQUA (-7050 1725);
DISPLAY INVISIBLE (-7050 1725);
FORCEPROP 1 LAST BODY_TYPE PLUMBING
J 0
(-7145 1657);
DISPLAY 0.340426 (-7145 1657);
PAINT GREEN (-7145 1657);
DISPLAY INVISIBLE (-7145 1657);
FORCEPROP 1 LAST HDL_POWER PVDDQ_GHJ
J 1
(-7100 1750);
DISPLAY 0.872340 (-7100 1750);
PAINT GREEN (-7100 1750);
DISPLAY INVISIBLE (-7100 1750);
FORCEADD GND..1
(-3600 2075);
FORCEPROP 3 LASTPIN (-3600 2125) SIG_NAME GND\g
J 0
(-3590 2135);
DISPLAY 0.659574 (-3590 2135);
PAINT MONO (-3590 2135);
DISPLAY INVISIBLE (-3590 2135);
FORCEPROP 2 LAST CDS_LIB mstr_symbols
J 0
(-3600 2075);
PAINT MONO (-3600 2075);
DISPLAY INVISIBLE (-3600 2075);
FORCEPROP 1 LAST SIZE 1B
J 0
(-3525 2025);
DISPLAY 1.723404 (-3525 2025);
PAINT GREEN (-3525 2025);
DISPLAY INVISIBLE (-3525 2025);
FORCEPROP 2 LAST BOM_COST PROC_VRD_VCCIN_CPU0
J 0
(-3975 2150);
DISPLAY 1.446809 (-3975 2150);
PAINT MONO (-3975 2150);
DISPLAY INVISIBLE (-3975 2150);
FORCEPROP 2 LAST ROOM VDDQ_ABC_PWR_VR
J 0
(-4150 2150);
DISPLAY 1.936170 (-4150 2150);
PAINT ORANGE (-4150 2150);
DISPLAY INVISIBLE (-4150 2150);
FORCEPROP 1 LAST VOLTAGE 0
J 0
(-3600 2075);
PAINT SKYBLUE (-3600 2075);
DISPLAY INVISIBLE (-3600 2075);
FORCEPROP 1 LAST PATH I34
J 0
(-3525 2075);
DISPLAY 0.872340 (-3525 2075);
PAINT AQUA (-3525 2075);
DISPLAY INVISIBLE (-3525 2075);
FORCEPROP 1 LAST BODY_TYPE PLUMBING
J 0
(-3645 2032);
DISPLAY 0.340426 (-3645 2032);
PAINT GREEN (-3645 2032);
DISPLAY INVISIBLE (-3645 2032);
FORCEPROP 1 LAST HDL_POWER GND
J 0
(-3600 2225);
DISPLAY 1.723404 (-3600 2225);
PAINT GREEN (-3600 2225);
DISPLAY INVISIBLE (-3600 2225);
FORCEADD PVDDQ_KLM..1
(-3600 2900);
FORCEPROP 3 LASTPIN (-3600 2850) SIG_NAME PVDDQ_KLM\g
J 0
(-3590 2860);
DISPLAY 0.659574 (-3590 2860);
PAINT MONO (-3590 2860);
DISPLAY INVISIBLE (-3590 2860);
FORCEPROP 2 LAST CDS_LIB mstr_symbols
J 0
(-3600 2900);
PAINT MONO (-3600 2900);
DISPLAY INVISIBLE (-3600 2900);
FORCEPROP 2 LAST BOM_COST VDDQ_KLM_PWR_VR
J 0
(-3600 3000);
DISPLAY 1.446809 (-3600 3000);
PAINT MONO (-3600 3000);
DISPLAY INVISIBLE (-3600 3000);
FORCEPROP 2 LAST ROOM VDDQ_KLM_PWR_VR
J 0
(-3600 3000);
DISPLAY 1.936170 (-3600 3000);
PAINT ORANGE (-3600 3000);
DISPLAY INVISIBLE (-3600 3000);
FORCEPROP 1 LAST VOLTAGE 1.2V
J 0
(-3645 2857);
DISPLAY 0.340426 (-3645 2857);
PAINT SKYBLUE (-3645 2857);
DISPLAY INVISIBLE (-3645 2857);
FORCEPROP 1 LAST PATH I36
J 0
(-3550 2925);
DISPLAY 0.872340 (-3550 2925);
PAINT AQUA (-3550 2925);
DISPLAY INVISIBLE (-3550 2925);
FORCEPROP 1 LAST BODY_TYPE PLUMBING
J 0
(-3645 2857);
DISPLAY 0.340426 (-3645 2857);
PAINT GREEN (-3645 2857);
DISPLAY INVISIBLE (-3645 2857);
FORCEPROP 1 LAST HDL_POWER PVDDQ_KLM
J 1
(-3600 2950);
DISPLAY 0.872340 (-3600 2950);
PAINT GREEN (-3600 2950);
DISPLAY INVISIBLE (-3600 2950);
FORCEADD GND..1
(-3600 3400);
FORCEPROP 3 LASTPIN (-3600 3450) SIG_NAME GND\g
J 0
(-3590 3460);
DISPLAY 0.659574 (-3590 3460);
PAINT MONO (-3590 3460);
DISPLAY INVISIBLE (-3590 3460);
FORCEPROP 2 LAST CDS_LIB mstr_symbols
J 0
(-3600 3400);
PAINT MONO (-3600 3400);
DISPLAY INVISIBLE (-3600 3400);
FORCEPROP 1 LAST SIZE 1B
J 0
(-3525 3350);
DISPLAY 1.723404 (-3525 3350);
PAINT GREEN (-3525 3350);
DISPLAY INVISIBLE (-3525 3350);
FORCEPROP 2 LAST BOM_COST PROC_VRD_VCCIN_CPU0
J 0
(-3975 3475);
DISPLAY 1.446809 (-3975 3475);
PAINT MONO (-3975 3475);
DISPLAY INVISIBLE (-3975 3475);
FORCEPROP 2 LAST ROOM VDDQ_ABC_PWR_VR
J 0
(-4150 3475);
DISPLAY 1.936170 (-4150 3475);
PAINT ORANGE (-4150 3475);
DISPLAY INVISIBLE (-4150 3475);
FORCEPROP 1 LAST VOLTAGE 0
J 0
(-3600 3400);
PAINT SKYBLUE (-3600 3400);
DISPLAY INVISIBLE (-3600 3400);
FORCEPROP 1 LAST PATH I38
J 0
(-3525 3400);
DISPLAY 0.872340 (-3525 3400);
PAINT AQUA (-3525 3400);
DISPLAY INVISIBLE (-3525 3400);
FORCEPROP 1 LAST BODY_TYPE PLUMBING
J 0
(-3645 3357);
DISPLAY 0.340426 (-3645 3357);
PAINT GREEN (-3645 3357);
DISPLAY INVISIBLE (-3645 3357);
FORCEPROP 1 LAST HDL_POWER GND
J 0
(-3600 3550);
DISPLAY 1.723404 (-3600 3550);
PAINT GREEN (-3600 3550);
DISPLAY INVISIBLE (-3600 3550);
FORCEADD CAP..1
(-3600 3925);
FORCEPROP 1 LAST PART_NUMBER 602433-112
J 0
(-3550 3775);
DISPLAY 0.617021 (-3550 3775);
PAINT BLUE (-3550 3775);
FORCEPROP 1 LAST VALUE 100UF
J 0
(-3550 3975);
DISPLAY 0.617021 (-3550 3975);
PAINT SKYBLUE (-3550 3975);
FORCEPROP 1 LAST LOCATION C5G115
J 0
(-3550 4025);
DISPLAY 0.617021 (-3550 4025);
PAINT AQUA (-3550 4025);
FORCEPROP 1 LAST PACK_TYPE 0805
J 0
(-3550 3725);
DISPLAY 0.617021 (-3550 3725);
PAINT SKYBLUE (-3550 3725);
FORCEPROP 1 LAST MATERIAL X5R
J 0
(-3550 3825);
DISPLAY 0.617021 (-3550 3825);
PAINT SKYBLUE (-3550 3825);
FORCEPROP 1 LAST VOLTAGE 4V
J 0
(-3550 3925);
DISPLAY 0.617021 (-3550 3925);
PAINT SKYBLUE (-3550 3925);
FORCEPROP 1 LAST TOLERANCE 20%
J 0
(-3550 3875);
DISPLAY 0.617021 (-3550 3875);
PAINT SKYBLUE (-3550 3875);
FORCEPROP 0 LAST SIDE_SKU 1S
J 0
(-3700 4000);
DISPLAY 1.021277 (-3700 4000);
PAINT ORANGE (-3700 4000);
FORCEPROP 1 LASTPIN (-3600 4025) $PN 1
J 0
(-3590 4005);
DISPLAY 0.787234 (-3590 4005);
PAINT ORANGE (-3590 4005);
DISPLAY INVISIBLE (-3590 4005);
FORCEPROP 1 LASTPIN (-3600 3825) $PN 2
J 0
(-3590 3805);
DISPLAY 0.787234 (-3590 3805);
PAINT ORANGE (-3590 3805);
DISPLAY INVISIBLE (-3590 3805);
FORCEPROP 2 LAST CDS_LIB mstr_discrete
J 0
(-3600 3925);
PAINT MONO (-3600 3925);
DISPLAY INVISIBLE (-3600 3925);
FORCEPROP 2 LAST BOM_COST MEM_VRD_PVDDQ_CD
J 0
(-3550 4075);
PAINT MONO (-3550 4075);
DISPLAY INVISIBLE (-3550 4075);
FORCEPROP 2 LAST ROOM VDDQ_KLM_PWR_VR
J 0
(-3550 4075);
PAINT MONO (-3550 4075);
DISPLAY INVISIBLE (-3550 4075);
FORCEPROP 0 LAST CDS_LOCATION C5G115
J 0
(-3550 4075);
PAINT MONO (-3550 4075);
DISPLAY INVISIBLE (-3550 4075);
FORCEPROP 0 LAST $SEC 1
J 0
(-3550 4075);
PAINT MONO (-3550 4075);
DISPLAY INVISIBLE (-3550 4075);
FORCEPROP 0 LAST CDS_SEC 1
J 0
(-3550 4075);
PAINT MONO (-3550 4075);
DISPLAY INVISIBLE (-3550 4075);
FORCEPROP 1 LAST PATH I39
J 0
(-3550 4075);
DISPLAY 0.978723 (-3550 4075);
PAINT WHITE (-3550 4075);
DISPLAY INVISIBLE (-3550 4075);
FORCEADD CAP..1
(-3200 3925);
FORCEPROP 1 LAST PART_NUMBER 602433-112
J 0
(-3150 3775);
DISPLAY 0.617021 (-3150 3775);
PAINT BLUE (-3150 3775);
FORCEPROP 1 LAST TOLERANCE 20%
J 0
(-3150 3875);
DISPLAY 0.617021 (-3150 3875);
PAINT SKYBLUE (-3150 3875);
FORCEPROP 1 LAST PACK_TYPE 0805
J 0
(-3150 3725);
DISPLAY 0.617021 (-3150 3725);
PAINT SKYBLUE (-3150 3725);
FORCEPROP 1 LAST LOCATION C5G116
J 0
(-3150 4025);
DISPLAY 0.617021 (-3150 4025);
PAINT AQUA (-3150 4025);
FORCEPROP 1 LAST VALUE 100UF
J 0
(-3150 3975);
DISPLAY 0.617021 (-3150 3975);
PAINT SKYBLUE (-3150 3975);
FORCEPROP 1 LAST VOLTAGE 4V
J 0
(-3150 3925);
DISPLAY 0.617021 (-3150 3925);
PAINT SKYBLUE (-3150 3925);
FORCEPROP 1 LAST MATERIAL X5R
J 0
(-3150 3825);
DISPLAY 0.617021 (-3150 3825);
PAINT SKYBLUE (-3150 3825);
FORCEPROP 0 LAST SIDE_SKU 1S
J 0
(-3300 4000);
DISPLAY 1.021277 (-3300 4000);
PAINT ORANGE (-3300 4000);
FORCEPROP 1 LASTPIN (-3200 4025) $PN 1
J 0
(-3190 4005);
DISPLAY 0.787234 (-3190 4005);
PAINT ORANGE (-3190 4005);
DISPLAY INVISIBLE (-3190 4005);
FORCEPROP 1 LASTPIN (-3200 3825) $PN 2
J 0
(-3190 3805);
DISPLAY 0.787234 (-3190 3805);
PAINT ORANGE (-3190 3805);
DISPLAY INVISIBLE (-3190 3805);
FORCEPROP 2 LAST CDS_LIB mstr_discrete
J 0
(-3200 3925);
PAINT MONO (-3200 3925);
DISPLAY INVISIBLE (-3200 3925);
FORCEPROP 2 LAST ROOM VDDQ_KLM_PWR_VR
J 0
(-3150 4075);
PAINT MONO (-3150 4075);
DISPLAY INVISIBLE (-3150 4075);
FORCEPROP 2 LAST BOM_COST MEM_VRD_PVDDQ_CD
J 0
(-3150 4075);
PAINT MONO (-3150 4075);
DISPLAY INVISIBLE (-3150 4075);
FORCEPROP 0 LAST CDS_LOCATION C5G116
J 0
(-3150 4075);
PAINT MONO (-3150 4075);
DISPLAY INVISIBLE (-3150 4075);
FORCEPROP 0 LAST $SEC 1
J 0
(-3150 4075);
PAINT MONO (-3150 4075);
DISPLAY INVISIBLE (-3150 4075);
FORCEPROP 0 LAST CDS_SEC 1
J 0
(-3150 4075);
PAINT MONO (-3150 4075);
DISPLAY INVISIBLE (-3150 4075);
FORCEPROP 1 LAST PATH I43
J 0
(-3150 4075);
DISPLAY 0.978723 (-3150 4075);
PAINT WHITE (-3150 4075);
DISPLAY INVISIBLE (-3150 4075);
FORCEADD PVDDQ_KLM..1
(-3600 4350);
FORCEPROP 3 LASTPIN (-3600 4300) SIG_NAME PVDDQ_KLM\g
J 0
(-3590 4310);
DISPLAY 0.659574 (-3590 4310);
PAINT MONO (-3590 4310);
DISPLAY INVISIBLE (-3590 4310);
FORCEPROP 2 LAST CDS_LIB mstr_symbols
J 0
(-3600 4350);
PAINT MONO (-3600 4350);
DISPLAY INVISIBLE (-3600 4350);
FORCEPROP 2 LAST BOM_COST VDDQ_KLM_PWR_VR
J 0
(-3600 4450);
DISPLAY 1.446809 (-3600 4450);
PAINT MONO (-3600 4450);
DISPLAY INVISIBLE (-3600 4450);
FORCEPROP 2 LAST ROOM VDDQ_KLM_PWR_VR
J 0
(-3600 4450);
DISPLAY 1.936170 (-3600 4450);
PAINT ORANGE (-3600 4450);
DISPLAY INVISIBLE (-3600 4450);
FORCEPROP 1 LAST VOLTAGE 1.2V
J 0
(-3645 4307);
DISPLAY 0.340426 (-3645 4307);
PAINT SKYBLUE (-3645 4307);
DISPLAY INVISIBLE (-3645 4307);
FORCEPROP 1 LAST PATH I51
J 0
(-3550 4375);
DISPLAY 0.872340 (-3550 4375);
PAINT AQUA (-3550 4375);
DISPLAY INVISIBLE (-3550 4375);
FORCEPROP 1 LAST BODY_TYPE PLUMBING
J 0
(-3645 4307);
DISPLAY 0.340426 (-3645 4307);
PAINT GREEN (-3645 4307);
DISPLAY INVISIBLE (-3645 4307);
FORCEPROP 1 LAST HDL_POWER PVDDQ_KLM
J 1
(-3600 4400);
DISPLAY 0.872340 (-3600 4400);
PAINT GREEN (-3600 4400);
DISPLAY INVISIBLE (-3600 4400);
FORCEADD CAP_A..1
(-7125 2500);
FORCEPROP 1 LAST VALUE 22.0UF
J 0
(-7075 2550);
DISPLAY 0.617021 (-7075 2550);
PAINT SKYBLUE (-7075 2550);
FORCEPROP 1 LAST PART_NUMBER E15431-004
J 0
(-7075 2350);
DISPLAY 0.617021 (-7075 2350);
PAINT BLUE (-7075 2350);
FORCEPROP 1 LAST TOLERANCE 20%
J 0
(-7075 2450);
DISPLAY 0.617021 (-7075 2450);
PAINT SKYBLUE (-7075 2450);
FORCEPROP 1 LAST VOLTAGE 4V
J 0
(-7075 2500);
DISPLAY 0.617021 (-7075 2500);
PAINT SKYBLUE (-7075 2500);
FORCEPROP 1 LAST MATERIAL X6S
J 0
(-7075 2400);
DISPLAY 0.617021 (-7075 2400);
PAINT SKYBLUE (-7075 2400);
FORCEPROP 1 LAST PACK_TYPE 0603V
J 0
(-7075 2300);
DISPLAY 0.617021 (-7075 2300);
PAINT SKYBLUE (-7075 2300);
FORCEPROP 1 LAST LOCATION C5G79
J 0
(-7075 2600);
DISPLAY 0.617021 (-7075 2600);
PAINT AQUA (-7075 2600);
FORCEPROP 0 LAST SIDE_SKU 1S
J 0
(-7250 2550);
DISPLAY 1.021277 (-7250 2550);
PAINT ORANGE (-7250 2550);
FORCEPROP 0 LAST ROOM PVDDQ_KLM
J 0
(-7075 2700);
DISPLAY 1.021277 (-7075 2700);
PAINT ORANGE (-7075 2700);
DISPLAY INVISIBLE (-7075 2700);
FORCEPROP 1 LAST PATH I53
J 0
(-7075 2650);
DISPLAY 0.978723 (-7075 2650);
PAINT WHITE (-7075 2650);
DISPLAY INVISIBLE (-7075 2650);
FORCEPROP 2 LAST CDS_LIB dev_discrete
J 0
(-7125 2500);
PAINT MONO (-7125 2500);
DISPLAY INVISIBLE (-7125 2500);
FORCEPROP 1 LASTPIN (-7125 2600) $PN 1
J 0
(-7115 2580);
DISPLAY 0.787234 (-7115 2580);
PAINT ORANGE (-7115 2580);
DISPLAY INVISIBLE (-7115 2580);
FORCEPROP 1 LASTPIN (-7125 2400) $PN 2
J 0
(-7115 2380);
DISPLAY 0.787234 (-7115 2380);
PAINT ORANGE (-7115 2380);
DISPLAY INVISIBLE (-7115 2380);
FORCEADD CAP_A..1
(-4650 2500);
FORCEPROP 1 LAST TOLERANCE 20%
J 0
(-4600 2450);
DISPLAY 0.617021 (-4600 2450);
PAINT SKYBLUE (-4600 2450);
FORCEPROP 1 LAST VOLTAGE 4V
J 0
(-4600 2500);
DISPLAY 0.617021 (-4600 2500);
PAINT SKYBLUE (-4600 2500);
FORCEPROP 1 LAST MATERIAL X6S
J 0
(-4600 2400);
DISPLAY 0.617021 (-4600 2400);
PAINT SKYBLUE (-4600 2400);
FORCEPROP 1 LAST PACK_TYPE 0603V
J 0
(-4600 2300);
DISPLAY 0.617021 (-4600 2300);
PAINT SKYBLUE (-4600 2300);
FORCEPROP 1 LAST PART_NUMBER E15431-004
J 0
(-4600 2350);
DISPLAY 0.617021 (-4600 2350);
PAINT BLUE (-4600 2350);
FORCEPROP 1 LAST VALUE 22.0UF
J 0
(-4600 2550);
DISPLAY 0.617021 (-4600 2550);
PAINT SKYBLUE (-4600 2550);
FORCEPROP 1 LAST LOCATION C5G87
J 0
(-4600 2600);
DISPLAY 0.617021 (-4600 2600);
PAINT AQUA (-4600 2600);
FORCEPROP 0 LAST SIDE_SKU 1S
J 0
(-4775 2550);
DISPLAY 1.021277 (-4775 2550);
PAINT ORANGE (-4775 2550);
FORCEPROP 0 LAST ROOM PVDDQ_KLM
J 0
(-4600 2700);
DISPLAY 1.021277 (-4600 2700);
PAINT ORANGE (-4600 2700);
DISPLAY INVISIBLE (-4600 2700);
FORCEPROP 1 LAST PATH I54
J 0
(-4600 2650);
DISPLAY 0.978723 (-4600 2650);
PAINT WHITE (-4600 2650);
DISPLAY INVISIBLE (-4600 2650);
FORCEPROP 2 LAST CDS_LIB dev_discrete
J 0
(-4650 2500);
PAINT MONO (-4650 2500);
DISPLAY INVISIBLE (-4650 2500);
FORCEPROP 1 LASTPIN (-4650 2600) $PN 1
J 0
(-4640 2580);
DISPLAY 0.787234 (-4640 2580);
PAINT ORANGE (-4640 2580);
DISPLAY INVISIBLE (-4640 2580);
FORCEPROP 1 LASTPIN (-4650 2400) $PN 2
J 0
(-4640 2380);
DISPLAY 0.787234 (-4640 2380);
PAINT ORANGE (-4640 2380);
DISPLAY INVISIBLE (-4640 2380);
FORCEADD CAP_A..1
(-4950 2500);
FORCEPROP 1 LAST VALUE 22.0UF
J 0
(-4900 2550);
DISPLAY 0.617021 (-4900 2550);
PAINT SKYBLUE (-4900 2550);
FORCEPROP 1 LAST PART_NUMBER E15431-004
J 0
(-4900 2350);
DISPLAY 0.617021 (-4900 2350);
PAINT BLUE (-4900 2350);
FORCEPROP 1 LAST TOLERANCE 20%
J 0
(-4900 2450);
DISPLAY 0.617021 (-4900 2450);
PAINT SKYBLUE (-4900 2450);
FORCEPROP 1 LAST VOLTAGE 4V
J 0
(-4900 2500);
DISPLAY 0.617021 (-4900 2500);
PAINT SKYBLUE (-4900 2500);
FORCEPROP 1 LAST MATERIAL X6S
J 0
(-4900 2400);
DISPLAY 0.617021 (-4900 2400);
PAINT SKYBLUE (-4900 2400);
FORCEPROP 1 LAST PACK_TYPE 0603V
J 0
(-4900 2300);
DISPLAY 0.617021 (-4900 2300);
PAINT SKYBLUE (-4900 2300);
FORCEPROP 1 LAST LOCATION C5G86
J 0
(-4900 2600);
DISPLAY 0.617021 (-4900 2600);
PAINT AQUA (-4900 2600);
FORCEPROP 0 LAST SIDE_SKU 1S
J 0
(-5075 2550);
DISPLAY 1.021277 (-5075 2550);
PAINT ORANGE (-5075 2550);
FORCEPROP 0 LAST ROOM PVDDQ_KLM
J 0
(-4900 2700);
DISPLAY 1.021277 (-4900 2700);
PAINT ORANGE (-4900 2700);
DISPLAY INVISIBLE (-4900 2700);
FORCEPROP 1 LAST PATH I55
J 0
(-4900 2650);
DISPLAY 0.978723 (-4900 2650);
PAINT WHITE (-4900 2650);
DISPLAY INVISIBLE (-4900 2650);
FORCEPROP 2 LAST CDS_LIB dev_discrete
J 0
(-4950 2500);
PAINT MONO (-4950 2500);
DISPLAY INVISIBLE (-4950 2500);
FORCEPROP 1 LASTPIN (-4950 2600) $PN 1
J 0
(-4940 2580);
DISPLAY 0.787234 (-4940 2580);
PAINT ORANGE (-4940 2580);
DISPLAY INVISIBLE (-4940 2580);
FORCEPROP 1 LASTPIN (-4950 2400) $PN 2
J 0
(-4940 2380);
DISPLAY 0.787234 (-4940 2380);
PAINT ORANGE (-4940 2380);
DISPLAY INVISIBLE (-4940 2380);
FORCEADD CAP_A..1
(-5250 2500);
FORCEPROP 1 LAST VALUE 22.0UF
J 0
(-5200 2550);
DISPLAY 0.617021 (-5200 2550);
PAINT SKYBLUE (-5200 2550);
FORCEPROP 1 LAST PART_NUMBER E15431-004
J 0
(-5200 2350);
DISPLAY 0.617021 (-5200 2350);
PAINT BLUE (-5200 2350);
FORCEPROP 1 LAST TOLERANCE 20%
J 0
(-5200 2450);
DISPLAY 0.617021 (-5200 2450);
PAINT SKYBLUE (-5200 2450);
FORCEPROP 1 LAST VOLTAGE 4V
J 0
(-5200 2500);
DISPLAY 0.617021 (-5200 2500);
PAINT SKYBLUE (-5200 2500);
FORCEPROP 1 LAST MATERIAL X6S
J 0
(-5200 2400);
DISPLAY 0.617021 (-5200 2400);
PAINT SKYBLUE (-5200 2400);
FORCEPROP 1 LAST PACK_TYPE 0603V
J 0
(-5200 2300);
DISPLAY 0.617021 (-5200 2300);
PAINT SKYBLUE (-5200 2300);
FORCEPROP 1 LAST LOCATION C5G85
J 0
(-5200 2600);
DISPLAY 0.617021 (-5200 2600);
PAINT AQUA (-5200 2600);
FORCEPROP 0 LAST SIDE_SKU 1S
J 0
(-5375 2550);
DISPLAY 1.021277 (-5375 2550);
PAINT ORANGE (-5375 2550);
FORCEPROP 0 LAST ROOM PVDDQ_KLM
J 0
(-5200 2700);
DISPLAY 1.021277 (-5200 2700);
PAINT ORANGE (-5200 2700);
DISPLAY INVISIBLE (-5200 2700);
FORCEPROP 1 LAST PATH I56
J 0
(-5200 2650);
DISPLAY 0.978723 (-5200 2650);
PAINT WHITE (-5200 2650);
DISPLAY INVISIBLE (-5200 2650);
FORCEPROP 2 LAST CDS_LIB dev_discrete
J 0
(-5250 2500);
PAINT MONO (-5250 2500);
DISPLAY INVISIBLE (-5250 2500);
FORCEPROP 1 LASTPIN (-5250 2600) $PN 1
J 0
(-5240 2580);
DISPLAY 0.787234 (-5240 2580);
PAINT ORANGE (-5240 2580);
DISPLAY INVISIBLE (-5240 2580);
FORCEPROP 1 LASTPIN (-5250 2400) $PN 2
J 0
(-5240 2380);
DISPLAY 0.787234 (-5240 2380);
PAINT ORANGE (-5240 2380);
DISPLAY INVISIBLE (-5240 2380);
FORCEADD CAP_A..1
(-5550 2500);
FORCEPROP 1 LAST VALUE 22.0UF
J 0
(-5500 2550);
DISPLAY 0.617021 (-5500 2550);
PAINT SKYBLUE (-5500 2550);
FORCEPROP 1 LAST PART_NUMBER E15431-004
J 0
(-5500 2350);
DISPLAY 0.617021 (-5500 2350);
PAINT BLUE (-5500 2350);
FORCEPROP 1 LAST TOLERANCE 20%
J 0
(-5500 2450);
DISPLAY 0.617021 (-5500 2450);
PAINT SKYBLUE (-5500 2450);
FORCEPROP 1 LAST VOLTAGE 4V
J 0
(-5500 2500);
DISPLAY 0.617021 (-5500 2500);
PAINT SKYBLUE (-5500 2500);
FORCEPROP 1 LAST MATERIAL X6S
J 0
(-5500 2400);
DISPLAY 0.617021 (-5500 2400);
PAINT SKYBLUE (-5500 2400);
FORCEPROP 1 LAST PACK_TYPE 0603V
J 0
(-5500 2300);
DISPLAY 0.617021 (-5500 2300);
PAINT SKYBLUE (-5500 2300);
FORCEPROP 1 LAST LOCATION C5G84
J 0
(-5500 2600);
DISPLAY 0.617021 (-5500 2600);
PAINT AQUA (-5500 2600);
FORCEPROP 0 LAST SIDE_SKU 1S
J 0
(-5675 2550);
DISPLAY 1.021277 (-5675 2550);
PAINT ORANGE (-5675 2550);
FORCEPROP 0 LAST ROOM PVDDQ_KLM
J 0
(-5500 2700);
DISPLAY 1.021277 (-5500 2700);
PAINT ORANGE (-5500 2700);
DISPLAY INVISIBLE (-5500 2700);
FORCEPROP 1 LAST PATH I57
J 0
(-5500 2650);
DISPLAY 0.978723 (-5500 2650);
PAINT WHITE (-5500 2650);
DISPLAY INVISIBLE (-5500 2650);
FORCEPROP 2 LAST CDS_LIB dev_discrete
J 0
(-5550 2500);
PAINT MONO (-5550 2500);
DISPLAY INVISIBLE (-5550 2500);
FORCEPROP 1 LASTPIN (-5550 2600) $PN 1
J 0
(-5540 2580);
DISPLAY 0.787234 (-5540 2580);
PAINT ORANGE (-5540 2580);
DISPLAY INVISIBLE (-5540 2580);
FORCEPROP 1 LASTPIN (-5550 2400) $PN 2
J 0
(-5540 2380);
DISPLAY 0.787234 (-5540 2380);
PAINT ORANGE (-5540 2380);
DISPLAY INVISIBLE (-5540 2380);
FORCEADD CAP_A..1
(-5850 2500);
FORCEPROP 1 LAST PACK_TYPE 0603V
J 0
(-5800 2300);
DISPLAY 0.617021 (-5800 2300);
PAINT SKYBLUE (-5800 2300);
FORCEPROP 1 LAST MATERIAL X6S
J 0
(-5800 2400);
DISPLAY 0.617021 (-5800 2400);
PAINT SKYBLUE (-5800 2400);
FORCEPROP 1 LAST PART_NUMBER E15431-004
J 0
(-5800 2350);
DISPLAY 0.617021 (-5800 2350);
PAINT BLUE (-5800 2350);
FORCEPROP 1 LAST LOCATION C5G83
J 0
(-5800 2600);
DISPLAY 0.617021 (-5800 2600);
PAINT AQUA (-5800 2600);
FORCEPROP 1 LAST VALUE 22.0UF
J 0
(-5800 2550);
DISPLAY 0.617021 (-5800 2550);
PAINT SKYBLUE (-5800 2550);
FORCEPROP 1 LAST VOLTAGE 4V
J 0
(-5800 2500);
DISPLAY 0.617021 (-5800 2500);
PAINT SKYBLUE (-5800 2500);
FORCEPROP 1 LAST TOLERANCE 20%
J 0
(-5800 2450);
DISPLAY 0.617021 (-5800 2450);
PAINT SKYBLUE (-5800 2450);
FORCEPROP 0 LAST SIDE_SKU 1S
J 0
(-5975 2550);
DISPLAY 1.021277 (-5975 2550);
PAINT ORANGE (-5975 2550);
FORCEPROP 0 LAST ROOM PVDDQ_KLM
J 0
(-5800 2700);
DISPLAY 1.021277 (-5800 2700);
PAINT ORANGE (-5800 2700);
DISPLAY INVISIBLE (-5800 2700);
FORCEPROP 1 LAST PATH I58
J 0
(-5800 2650);
DISPLAY 0.978723 (-5800 2650);
PAINT WHITE (-5800 2650);
DISPLAY INVISIBLE (-5800 2650);
FORCEPROP 2 LAST CDS_LIB dev_discrete
J 0
(-5850 2500);
PAINT MONO (-5850 2500);
DISPLAY INVISIBLE (-5850 2500);
FORCEPROP 1 LASTPIN (-5850 2600) $PN 1
J 0
(-5840 2580);
DISPLAY 0.787234 (-5840 2580);
PAINT ORANGE (-5840 2580);
DISPLAY INVISIBLE (-5840 2580);
FORCEPROP 1 LASTPIN (-5850 2400) $PN 2
J 0
(-5840 2380);
DISPLAY 0.787234 (-5840 2380);
PAINT ORANGE (-5840 2380);
DISPLAY INVISIBLE (-5840 2380);
FORCEADD CAP_A..1
(-6150 2500);
FORCEPROP 1 LAST PACK_TYPE 0603V
J 0
(-6100 2300);
DISPLAY 0.617021 (-6100 2300);
PAINT SKYBLUE (-6100 2300);
FORCEPROP 1 LAST MATERIAL X6S
J 0
(-6100 2400);
DISPLAY 0.617021 (-6100 2400);
PAINT SKYBLUE (-6100 2400);
FORCEPROP 1 LAST VOLTAGE 4V
J 0
(-6100 2500);
DISPLAY 0.617021 (-6100 2500);
PAINT SKYBLUE (-6100 2500);
FORCEPROP 1 LAST TOLERANCE 20%
J 0
(-6100 2450);
DISPLAY 0.617021 (-6100 2450);
PAINT SKYBLUE (-6100 2450);
FORCEPROP 1 LAST PART_NUMBER E15431-004
J 0
(-6100 2350);
DISPLAY 0.617021 (-6100 2350);
PAINT BLUE (-6100 2350);
FORCEPROP 1 LAST VALUE 22.0UF
J 0
(-6100 2550);
DISPLAY 0.617021 (-6100 2550);
PAINT SKYBLUE (-6100 2550);
FORCEPROP 1 LAST LOCATION C5G82
J 0
(-6100 2600);
DISPLAY 0.617021 (-6100 2600);
PAINT AQUA (-6100 2600);
FORCEPROP 0 LAST SIDE_SKU 1S
J 0
(-6275 2550);
DISPLAY 1.021277 (-6275 2550);
PAINT ORANGE (-6275 2550);
FORCEPROP 0 LAST ROOM PVDDQ_KLM
J 0
(-6100 2700);
DISPLAY 1.021277 (-6100 2700);
PAINT ORANGE (-6100 2700);
DISPLAY INVISIBLE (-6100 2700);
FORCEPROP 1 LAST PATH I59
J 0
(-6100 2650);
DISPLAY 0.978723 (-6100 2650);
PAINT WHITE (-6100 2650);
DISPLAY INVISIBLE (-6100 2650);
FORCEPROP 2 LAST CDS_LIB dev_discrete
J 0
(-6150 2500);
PAINT MONO (-6150 2500);
DISPLAY INVISIBLE (-6150 2500);
FORCEPROP 1 LASTPIN (-6150 2600) $PN 1
J 0
(-6140 2580);
DISPLAY 0.787234 (-6140 2580);
PAINT ORANGE (-6140 2580);
DISPLAY INVISIBLE (-6140 2580);
FORCEPROP 1 LASTPIN (-6150 2400) $PN 2
J 0
(-6140 2380);
DISPLAY 0.787234 (-6140 2380);
PAINT ORANGE (-6140 2380);
DISPLAY INVISIBLE (-6140 2380);
FORCEADD GND..1
(-7125 2000);
FORCEPROP 3 LASTPIN (-7125 2050) SIG_NAME GND\g
J 0
(-7115 2060);
DISPLAY 0.659574 (-7115 2060);
PAINT MONO (-7115 2060);
DISPLAY INVISIBLE (-7115 2060);
FORCEPROP 2 LAST CDS_LIB mstr_symbols
J 0
(-7125 2000);
PAINT MONO (-7125 2000);
DISPLAY INVISIBLE (-7125 2000);
FORCEPROP 1 LAST SIZE 1B
J 0
(-7050 1950);
DISPLAY 1.723404 (-7050 1950);
PAINT GREEN (-7050 1950);
DISPLAY INVISIBLE (-7050 1950);
FORCEPROP 2 LAST BOM_COST PROC_VRD_VCCIN_CPU0
J 0
(-7500 2075);
DISPLAY 1.446809 (-7500 2075);
PAINT MONO (-7500 2075);
DISPLAY INVISIBLE (-7500 2075);
FORCEPROP 2 LAST ROOM VDDQ_ABC_PWR_VR
J 0
(-7675 2075);
DISPLAY 1.936170 (-7675 2075);
PAINT ORANGE (-7675 2075);
DISPLAY INVISIBLE (-7675 2075);
FORCEPROP 1 LAST VOLTAGE 0
J 0
(-7125 2000);
PAINT SKYBLUE (-7125 2000);
DISPLAY INVISIBLE (-7125 2000);
FORCEPROP 1 LAST PATH I6
J 0
(-7050 2000);
DISPLAY 0.872340 (-7050 2000);
PAINT AQUA (-7050 2000);
DISPLAY INVISIBLE (-7050 2000);
FORCEPROP 1 LAST BODY_TYPE PLUMBING
J 0
(-7170 1957);
DISPLAY 0.340426 (-7170 1957);
PAINT GREEN (-7170 1957);
DISPLAY INVISIBLE (-7170 1957);
FORCEPROP 1 LAST HDL_POWER GND
J 0
(-7125 2150);
DISPLAY 1.723404 (-7125 2150);
PAINT GREEN (-7125 2150);
DISPLAY INVISIBLE (-7125 2150);
FORCEADD CAP_A..1
(-6500 2500);
FORCEPROP 1 LAST VALUE 22.0UF
J 0
(-6450 2550);
DISPLAY 0.617021 (-6450 2550);
PAINT SKYBLUE (-6450 2550);
FORCEPROP 1 LAST PART_NUMBER E15431-004
J 0
(-6450 2350);
DISPLAY 0.617021 (-6450 2350);
PAINT BLUE (-6450 2350);
FORCEPROP 1 LAST TOLERANCE 20%
J 0
(-6450 2450);
DISPLAY 0.617021 (-6450 2450);
PAINT SKYBLUE (-6450 2450);
FORCEPROP 1 LAST VOLTAGE 4V
J 0
(-6450 2500);
DISPLAY 0.617021 (-6450 2500);
PAINT SKYBLUE (-6450 2500);
FORCEPROP 1 LAST MATERIAL X6S
J 0
(-6450 2400);
DISPLAY 0.617021 (-6450 2400);
PAINT SKYBLUE (-6450 2400);
FORCEPROP 1 LAST PACK_TYPE 0603V
J 0
(-6450 2300);
DISPLAY 0.617021 (-6450 2300);
PAINT SKYBLUE (-6450 2300);
FORCEPROP 1 LAST LOCATION C5G81
J 0
(-6450 2600);
DISPLAY 0.617021 (-6450 2600);
PAINT AQUA (-6450 2600);
FORCEPROP 0 LAST SIDE_SKU 1S
J 0
(-6625 2550);
DISPLAY 1.021277 (-6625 2550);
PAINT ORANGE (-6625 2550);
FORCEPROP 0 LAST ROOM PVDDQ_KLM
J 0
(-6450 2700);
DISPLAY 1.021277 (-6450 2700);
PAINT ORANGE (-6450 2700);
DISPLAY INVISIBLE (-6450 2700);
FORCEPROP 1 LAST PATH I60
J 0
(-6450 2650);
DISPLAY 0.978723 (-6450 2650);
PAINT WHITE (-6450 2650);
DISPLAY INVISIBLE (-6450 2650);
FORCEPROP 2 LAST CDS_LIB dev_discrete
J 0
(-6500 2500);
PAINT MONO (-6500 2500);
DISPLAY INVISIBLE (-6500 2500);
FORCEPROP 1 LASTPIN (-6500 2600) $PN 1
J 0
(-6490 2580);
DISPLAY 0.787234 (-6490 2580);
PAINT ORANGE (-6490 2580);
DISPLAY INVISIBLE (-6490 2580);
FORCEPROP 1 LASTPIN (-6500 2400) $PN 2
J 0
(-6490 2380);
DISPLAY 0.787234 (-6490 2380);
PAINT ORANGE (-6490 2380);
DISPLAY INVISIBLE (-6490 2380);
FORCEADD CAP_A..1
(-6800 2500);
FORCEPROP 1 LAST VALUE 22.0UF
J 0
(-6750 2550);
DISPLAY 0.617021 (-6750 2550);
PAINT SKYBLUE (-6750 2550);
FORCEPROP 1 LAST PART_NUMBER E15431-004
J 0
(-6750 2350);
DISPLAY 0.617021 (-6750 2350);
PAINT BLUE (-6750 2350);
FORCEPROP 1 LAST TOLERANCE 20%
J 0
(-6750 2450);
DISPLAY 0.617021 (-6750 2450);
PAINT SKYBLUE (-6750 2450);
FORCEPROP 1 LAST VOLTAGE 4V
J 0
(-6750 2500);
DISPLAY 0.617021 (-6750 2500);
PAINT SKYBLUE (-6750 2500);
FORCEPROP 1 LAST MATERIAL X6S
J 0
(-6750 2400);
DISPLAY 0.617021 (-6750 2400);
PAINT SKYBLUE (-6750 2400);
FORCEPROP 1 LAST PACK_TYPE 0603V
J 0
(-6750 2300);
DISPLAY 0.617021 (-6750 2300);
PAINT SKYBLUE (-6750 2300);
FORCEPROP 1 LAST LOCATION C5G80
J 0
(-6750 2600);
DISPLAY 0.617021 (-6750 2600);
PAINT AQUA (-6750 2600);
FORCEPROP 0 LAST SIDE_SKU 1S
J 0
(-6925 2550);
DISPLAY 1.021277 (-6925 2550);
PAINT ORANGE (-6925 2550);
FORCEPROP 0 LAST ROOM PVDDQ_KLM
J 0
(-6750 2700);
DISPLAY 1.021277 (-6750 2700);
PAINT ORANGE (-6750 2700);
DISPLAY INVISIBLE (-6750 2700);
FORCEPROP 1 LAST PATH I61
J 0
(-6750 2650);
DISPLAY 0.978723 (-6750 2650);
PAINT WHITE (-6750 2650);
DISPLAY INVISIBLE (-6750 2650);
FORCEPROP 2 LAST CDS_LIB dev_discrete
J 0
(-6800 2500);
PAINT MONO (-6800 2500);
DISPLAY INVISIBLE (-6800 2500);
FORCEPROP 1 LASTPIN (-6800 2600) $PN 1
J 0
(-6790 2580);
DISPLAY 0.787234 (-6790 2580);
PAINT ORANGE (-6790 2580);
DISPLAY INVISIBLE (-6790 2580);
FORCEPROP 1 LASTPIN (-6800 2400) $PN 2
J 0
(-6790 2380);
DISPLAY 0.787234 (-6790 2380);
PAINT ORANGE (-6790 2380);
DISPLAY INVISIBLE (-6790 2380);
FORCEADD CAP_A..1
(-4650 1375);
FORCEPROP 1 LAST LOCATION C5G96
J 0
(-4600 1475);
DISPLAY 0.617021 (-4600 1475);
PAINT AQUA (-4600 1475);
FORCEPROP 1 LAST MATERIAL X6S
J 0
(-4600 1275);
DISPLAY 0.617021 (-4600 1275);
PAINT SKYBLUE (-4600 1275);
FORCEPROP 1 LAST VOLTAGE 4V
J 0
(-4600 1375);
DISPLAY 0.617021 (-4600 1375);
PAINT SKYBLUE (-4600 1375);
FORCEPROP 1 LAST TOLERANCE 20%
J 0
(-4600 1325);
DISPLAY 0.617021 (-4600 1325);
PAINT SKYBLUE (-4600 1325);
FORCEPROP 1 LAST VALUE 22.0UF
J 0
(-4600 1425);
DISPLAY 0.617021 (-4600 1425);
PAINT SKYBLUE (-4600 1425);
FORCEPROP 1 LAST PACK_TYPE 0603V
J 0
(-4600 1175);
DISPLAY 0.617021 (-4600 1175);
PAINT SKYBLUE (-4600 1175);
FORCEPROP 1 LAST PART_NUMBER E15431-004
J 0
(-4600 1225);
DISPLAY 0.617021 (-4600 1225);
PAINT BLUE (-4600 1225);
FORCEPROP 0 LAST SIDE_SKU 1S
J 0
(-4775 1425);
DISPLAY 1.021277 (-4775 1425);
PAINT ORANGE (-4775 1425);
FORCEPROP 2 LAST CDS_LIB dev_discrete
J 0
(-4650 1375);
PAINT MONO (-4650 1375);
DISPLAY INVISIBLE (-4650 1375);
FORCEPROP 1 LAST PATH I62
J 0
(-4600 1525);
DISPLAY 0.978723 (-4600 1525);
PAINT WHITE (-4600 1525);
DISPLAY INVISIBLE (-4600 1525);
FORCEPROP 0 LAST ROOM PVDDQ_KLM
J 0
(-4600 1575);
DISPLAY 1.021277 (-4600 1575);
PAINT ORANGE (-4600 1575);
DISPLAY INVISIBLE (-4600 1575);
FORCEPROP 1 LASTPIN (-4650 1475) $PN 1
J 0
(-4640 1455);
DISPLAY 0.787234 (-4640 1455);
PAINT ORANGE (-4640 1455);
DISPLAY INVISIBLE (-4640 1455);
FORCEPROP 1 LASTPIN (-4650 1275) $PN 2
J 0
(-4640 1255);
DISPLAY 0.787234 (-4640 1255);
PAINT ORANGE (-4640 1255);
DISPLAY INVISIBLE (-4640 1255);
FORCEADD CAP_A..1
(-4950 1375);
FORCEPROP 1 LAST VALUE 22.0UF
J 0
(-4900 1425);
DISPLAY 0.617021 (-4900 1425);
PAINT SKYBLUE (-4900 1425);
FORCEPROP 1 LAST LOCATION C5G95
J 0
(-4900 1475);
DISPLAY 0.617021 (-4900 1475);
PAINT AQUA (-4900 1475);
FORCEPROP 1 LAST VOLTAGE 4V
J 0
(-4900 1375);
DISPLAY 0.617021 (-4900 1375);
PAINT SKYBLUE (-4900 1375);
FORCEPROP 1 LAST PACK_TYPE 0603V
J 0
(-4900 1175);
DISPLAY 0.617021 (-4900 1175);
PAINT SKYBLUE (-4900 1175);
FORCEPROP 1 LAST MATERIAL X6S
J 0
(-4900 1275);
DISPLAY 0.617021 (-4900 1275);
PAINT SKYBLUE (-4900 1275);
FORCEPROP 1 LAST TOLERANCE 20%
J 0
(-4900 1325);
DISPLAY 0.617021 (-4900 1325);
PAINT SKYBLUE (-4900 1325);
FORCEPROP 1 LAST PART_NUMBER E15431-004
J 0
(-4900 1225);
DISPLAY 0.617021 (-4900 1225);
PAINT BLUE (-4900 1225);
FORCEPROP 0 LAST SIDE_SKU 1S
J 0
(-5075 1425);
DISPLAY 1.021277 (-5075 1425);
PAINT ORANGE (-5075 1425);
FORCEPROP 2 LAST CDS_LIB dev_discrete
J 0
(-4950 1375);
PAINT MONO (-4950 1375);
DISPLAY INVISIBLE (-4950 1375);
FORCEPROP 1 LAST PATH I63
J 0
(-4900 1525);
DISPLAY 0.978723 (-4900 1525);
PAINT WHITE (-4900 1525);
DISPLAY INVISIBLE (-4900 1525);
FORCEPROP 0 LAST ROOM PVDDQ_KLM
J 0
(-4900 1575);
DISPLAY 1.021277 (-4900 1575);
PAINT ORANGE (-4900 1575);
DISPLAY INVISIBLE (-4900 1575);
FORCEPROP 1 LASTPIN (-4950 1475) $PN 1
J 0
(-4940 1455);
DISPLAY 0.787234 (-4940 1455);
PAINT ORANGE (-4940 1455);
DISPLAY INVISIBLE (-4940 1455);
FORCEPROP 1 LASTPIN (-4950 1275) $PN 2
J 0
(-4940 1255);
DISPLAY 0.787234 (-4940 1255);
PAINT ORANGE (-4940 1255);
DISPLAY INVISIBLE (-4940 1255);
FORCEADD CAP_A..1
(-5250 1375);
FORCEPROP 1 LAST PACK_TYPE 0603V
J 0
(-5200 1175);
DISPLAY 0.617021 (-5200 1175);
PAINT SKYBLUE (-5200 1175);
FORCEPROP 1 LAST LOCATION C5G94
J 0
(-5200 1475);
DISPLAY 0.617021 (-5200 1475);
PAINT AQUA (-5200 1475);
FORCEPROP 1 LAST VALUE 22.0UF
J 0
(-5200 1425);
DISPLAY 0.617021 (-5200 1425);
PAINT SKYBLUE (-5200 1425);
FORCEPROP 1 LAST TOLERANCE 20%
J 0
(-5200 1325);
DISPLAY 0.617021 (-5200 1325);
PAINT SKYBLUE (-5200 1325);
FORCEPROP 1 LAST VOLTAGE 4V
J 0
(-5200 1375);
DISPLAY 0.617021 (-5200 1375);
PAINT SKYBLUE (-5200 1375);
FORCEPROP 1 LAST MATERIAL X6S
J 0
(-5200 1275);
DISPLAY 0.617021 (-5200 1275);
PAINT SKYBLUE (-5200 1275);
FORCEPROP 1 LAST PART_NUMBER E15431-004
J 0
(-5200 1225);
DISPLAY 0.617021 (-5200 1225);
PAINT BLUE (-5200 1225);
FORCEPROP 0 LAST SIDE_SKU 1S
J 0
(-5375 1425);
DISPLAY 1.021277 (-5375 1425);
PAINT ORANGE (-5375 1425);
FORCEPROP 2 LAST CDS_LIB dev_discrete
J 0
(-5250 1375);
PAINT MONO (-5250 1375);
DISPLAY INVISIBLE (-5250 1375);
FORCEPROP 1 LAST PATH I64
J 0
(-5200 1525);
DISPLAY 0.978723 (-5200 1525);
PAINT WHITE (-5200 1525);
DISPLAY INVISIBLE (-5200 1525);
FORCEPROP 0 LAST ROOM PVDDQ_KLM
J 0
(-5200 1575);
DISPLAY 1.021277 (-5200 1575);
PAINT ORANGE (-5200 1575);
DISPLAY INVISIBLE (-5200 1575);
FORCEPROP 1 LASTPIN (-5250 1475) $PN 1
J 0
(-5240 1455);
DISPLAY 0.787234 (-5240 1455);
PAINT ORANGE (-5240 1455);
DISPLAY INVISIBLE (-5240 1455);
FORCEPROP 1 LASTPIN (-5250 1275) $PN 2
J 0
(-5240 1255);
DISPLAY 0.787234 (-5240 1255);
PAINT ORANGE (-5240 1255);
DISPLAY INVISIBLE (-5240 1255);
FORCEADD CAP_A..1
(-5550 1375);
FORCEPROP 1 LAST LOCATION C5G93
J 0
(-5500 1475);
DISPLAY 0.617021 (-5500 1475);
PAINT AQUA (-5500 1475);
FORCEPROP 1 LAST VALUE 22.0UF
J 0
(-5500 1425);
DISPLAY 0.617021 (-5500 1425);
PAINT SKYBLUE (-5500 1425);
FORCEPROP 1 LAST TOLERANCE 20%
J 0
(-5500 1325);
DISPLAY 0.617021 (-5500 1325);
PAINT SKYBLUE (-5500 1325);
FORCEPROP 1 LAST VOLTAGE 4V
J 0
(-5500 1375);
DISPLAY 0.617021 (-5500 1375);
PAINT SKYBLUE (-5500 1375);
FORCEPROP 1 LAST PACK_TYPE 0603V
J 0
(-5500 1175);
DISPLAY 0.617021 (-5500 1175);
PAINT SKYBLUE (-5500 1175);
FORCEPROP 1 LAST MATERIAL X6S
J 0
(-5500 1275);
DISPLAY 0.617021 (-5500 1275);
PAINT SKYBLUE (-5500 1275);
FORCEPROP 1 LAST PART_NUMBER E15431-004
J 0
(-5500 1225);
DISPLAY 0.617021 (-5500 1225);
PAINT BLUE (-5500 1225);
FORCEPROP 0 LAST SIDE_SKU 1S
J 0
(-5675 1425);
DISPLAY 1.021277 (-5675 1425);
PAINT ORANGE (-5675 1425);
FORCEPROP 2 LAST CDS_LIB dev_discrete
J 0
(-5550 1375);
PAINT MONO (-5550 1375);
DISPLAY INVISIBLE (-5550 1375);
FORCEPROP 1 LAST PATH I65
J 0
(-5500 1525);
DISPLAY 0.978723 (-5500 1525);
PAINT WHITE (-5500 1525);
DISPLAY INVISIBLE (-5500 1525);
FORCEPROP 0 LAST ROOM PVDDQ_KLM
J 0
(-5500 1575);
DISPLAY 1.021277 (-5500 1575);
PAINT ORANGE (-5500 1575);
DISPLAY INVISIBLE (-5500 1575);
FORCEPROP 1 LASTPIN (-5550 1475) $PN 1
J 0
(-5540 1455);
DISPLAY 0.787234 (-5540 1455);
PAINT ORANGE (-5540 1455);
DISPLAY INVISIBLE (-5540 1455);
FORCEPROP 1 LASTPIN (-5550 1275) $PN 2
J 0
(-5540 1255);
DISPLAY 0.787234 (-5540 1255);
PAINT ORANGE (-5540 1255);
DISPLAY INVISIBLE (-5540 1255);
FORCEADD CAP_A..1
(-5850 1375);
FORCEPROP 1 LAST PART_NUMBER E15431-004
J 0
(-5800 1225);
DISPLAY 0.617021 (-5800 1225);
PAINT BLUE (-5800 1225);
FORCEPROP 1 LAST PACK_TYPE 0603V
J 0
(-5800 1175);
DISPLAY 0.617021 (-5800 1175);
PAINT SKYBLUE (-5800 1175);
FORCEPROP 1 LAST LOCATION C5G92
J 0
(-5800 1475);
DISPLAY 0.617021 (-5800 1475);
PAINT AQUA (-5800 1475);
FORCEPROP 1 LAST VOLTAGE 4V
J 0
(-5800 1375);
DISPLAY 0.617021 (-5800 1375);
PAINT SKYBLUE (-5800 1375);
FORCEPROP 1 LAST TOLERANCE 20%
J 0
(-5800 1325);
DISPLAY 0.617021 (-5800 1325);
PAINT SKYBLUE (-5800 1325);
FORCEPROP 1 LAST VALUE 22.0UF
J 0
(-5800 1425);
DISPLAY 0.617021 (-5800 1425);
PAINT SKYBLUE (-5800 1425);
FORCEPROP 1 LAST MATERIAL X6S
J 0
(-5800 1275);
DISPLAY 0.617021 (-5800 1275);
PAINT SKYBLUE (-5800 1275);
FORCEPROP 0 LAST SIDE_SKU 1S
J 0
(-5975 1425);
DISPLAY 1.021277 (-5975 1425);
PAINT ORANGE (-5975 1425);
FORCEPROP 2 LAST CDS_LIB dev_discrete
J 0
(-5850 1375);
PAINT MONO (-5850 1375);
DISPLAY INVISIBLE (-5850 1375);
FORCEPROP 1 LAST PATH I66
J 0
(-5800 1525);
DISPLAY 0.978723 (-5800 1525);
PAINT WHITE (-5800 1525);
DISPLAY INVISIBLE (-5800 1525);
FORCEPROP 0 LAST ROOM PVDDQ_KLM
J 0
(-5800 1575);
DISPLAY 1.021277 (-5800 1575);
PAINT ORANGE (-5800 1575);
DISPLAY INVISIBLE (-5800 1575);
FORCEPROP 1 LASTPIN (-5850 1475) $PN 1
J 0
(-5840 1455);
DISPLAY 0.787234 (-5840 1455);
PAINT ORANGE (-5840 1455);
DISPLAY INVISIBLE (-5840 1455);
FORCEPROP 1 LASTPIN (-5850 1275) $PN 2
J 0
(-5840 1255);
DISPLAY 0.787234 (-5840 1255);
PAINT ORANGE (-5840 1255);
DISPLAY INVISIBLE (-5840 1255);
FORCEADD CAP_A..1
(-6150 1375);
FORCEPROP 1 LAST TOLERANCE 20%
J 0
(-6100 1325);
DISPLAY 0.617021 (-6100 1325);
PAINT SKYBLUE (-6100 1325);
FORCEPROP 1 LAST LOCATION C5G91
J 0
(-6100 1475);
DISPLAY 0.617021 (-6100 1475);
PAINT AQUA (-6100 1475);
FORCEPROP 1 LAST VOLTAGE 4V
J 0
(-6100 1375);
DISPLAY 0.617021 (-6100 1375);
PAINT SKYBLUE (-6100 1375);
FORCEPROP 1 LAST PACK_TYPE 0603V
J 0
(-6100 1175);
DISPLAY 0.617021 (-6100 1175);
PAINT SKYBLUE (-6100 1175);
FORCEPROP 1 LAST PART_NUMBER E15431-004
J 0
(-6100 1225);
DISPLAY 0.617021 (-6100 1225);
PAINT BLUE (-6100 1225);
FORCEPROP 1 LAST MATERIAL X6S
J 0
(-6100 1275);
DISPLAY 0.617021 (-6100 1275);
PAINT SKYBLUE (-6100 1275);
FORCEPROP 1 LAST VALUE 22.0UF
J 0
(-6100 1425);
DISPLAY 0.617021 (-6100 1425);
PAINT SKYBLUE (-6100 1425);
FORCEPROP 0 LAST SIDE_SKU 1S
J 0
(-6275 1425);
DISPLAY 1.021277 (-6275 1425);
PAINT ORANGE (-6275 1425);
FORCEPROP 0 LAST ROOM PVDDQ_KLM
J 0
(-6100 1575);
DISPLAY 1.021277 (-6100 1575);
PAINT ORANGE (-6100 1575);
DISPLAY INVISIBLE (-6100 1575);
FORCEPROP 1 LAST PATH I67
J 0
(-6100 1525);
DISPLAY 0.978723 (-6100 1525);
PAINT WHITE (-6100 1525);
DISPLAY INVISIBLE (-6100 1525);
FORCEPROP 2 LAST CDS_LIB dev_discrete
J 0
(-6150 1375);
PAINT MONO (-6150 1375);
DISPLAY INVISIBLE (-6150 1375);
FORCEPROP 1 LASTPIN (-6150 1475) $PN 1
J 0
(-6140 1455);
DISPLAY 0.787234 (-6140 1455);
PAINT ORANGE (-6140 1455);
DISPLAY INVISIBLE (-6140 1455);
FORCEPROP 1 LASTPIN (-6150 1275) $PN 2
J 0
(-6140 1255);
DISPLAY 0.787234 (-6140 1255);
PAINT ORANGE (-6140 1255);
DISPLAY INVISIBLE (-6140 1255);
FORCEADD CAP_A..1
(-6450 1375);
FORCEPROP 1 LAST PACK_TYPE 0603V
J 0
(-6400 1175);
DISPLAY 0.617021 (-6400 1175);
PAINT SKYBLUE (-6400 1175);
FORCEPROP 1 LAST PART_NUMBER E15431-004
J 0
(-6400 1225);
DISPLAY 0.617021 (-6400 1225);
PAINT BLUE (-6400 1225);
FORCEPROP 1 LAST MATERIAL X6S
J 0
(-6400 1275);
DISPLAY 0.617021 (-6400 1275);
PAINT SKYBLUE (-6400 1275);
FORCEPROP 1 LAST TOLERANCE 20%
J 0
(-6400 1325);
DISPLAY 0.617021 (-6400 1325);
PAINT SKYBLUE (-6400 1325);
FORCEPROP 1 LAST VOLTAGE 4V
J 0
(-6400 1375);
DISPLAY 0.617021 (-6400 1375);
PAINT SKYBLUE (-6400 1375);
FORCEPROP 1 LAST VALUE 22.0UF
J 0
(-6400 1425);
DISPLAY 0.617021 (-6400 1425);
PAINT SKYBLUE (-6400 1425);
FORCEPROP 1 LAST LOCATION C5G90
J 0
(-6400 1475);
DISPLAY 0.617021 (-6400 1475);
PAINT AQUA (-6400 1475);
FORCEPROP 0 LAST SIDE_SKU 1S
J 0
(-6575 1425);
DISPLAY 1.021277 (-6575 1425);
PAINT ORANGE (-6575 1425);
FORCEPROP 2 LAST CDS_LIB dev_discrete
J 0
(-6450 1375);
PAINT MONO (-6450 1375);
DISPLAY INVISIBLE (-6450 1375);
FORCEPROP 1 LAST PATH I68
J 0
(-6400 1525);
DISPLAY 0.978723 (-6400 1525);
PAINT WHITE (-6400 1525);
DISPLAY INVISIBLE (-6400 1525);
FORCEPROP 0 LAST ROOM PVDDQ_KLM
J 0
(-6400 1575);
DISPLAY 1.021277 (-6400 1575);
PAINT ORANGE (-6400 1575);
DISPLAY INVISIBLE (-6400 1575);
FORCEPROP 1 LASTPIN (-6450 1475) $PN 1
J 0
(-6440 1455);
DISPLAY 0.787234 (-6440 1455);
PAINT ORANGE (-6440 1455);
DISPLAY INVISIBLE (-6440 1455);
FORCEPROP 1 LASTPIN (-6450 1275) $PN 2
J 0
(-6440 1255);
DISPLAY 0.787234 (-6440 1255);
PAINT ORANGE (-6440 1255);
DISPLAY INVISIBLE (-6440 1255);
FORCEADD CAP_A..1
(-6775 1375);
FORCEPROP 1 LAST TOLERANCE 20%
J 0
(-6725 1325);
DISPLAY 0.617021 (-6725 1325);
PAINT SKYBLUE (-6725 1325);
FORCEPROP 1 LAST LOCATION C5G89
J 0
(-6725 1475);
DISPLAY 0.617021 (-6725 1475);
PAINT AQUA (-6725 1475);
FORCEPROP 1 LAST MATERIAL X6S
J 0
(-6725 1275);
DISPLAY 0.617021 (-6725 1275);
PAINT SKYBLUE (-6725 1275);
FORCEPROP 1 LAST VALUE 22.0UF
J 0
(-6725 1425);
DISPLAY 0.617021 (-6725 1425);
PAINT SKYBLUE (-6725 1425);
FORCEPROP 1 LAST PART_NUMBER E15431-004
J 0
(-6725 1225);
DISPLAY 0.617021 (-6725 1225);
PAINT BLUE (-6725 1225);
FORCEPROP 1 LAST VOLTAGE 4V
J 0
(-6725 1375);
DISPLAY 0.617021 (-6725 1375);
PAINT SKYBLUE (-6725 1375);
FORCEPROP 1 LAST PACK_TYPE 0603V
J 0
(-6725 1175);
DISPLAY 0.617021 (-6725 1175);
PAINT SKYBLUE (-6725 1175);
FORCEPROP 0 LAST SIDE_SKU 1S
J 0
(-6900 1425);
DISPLAY 1.021277 (-6900 1425);
PAINT ORANGE (-6900 1425);
FORCEPROP 2 LAST CDS_LIB dev_discrete
J 0
(-6775 1375);
PAINT MONO (-6775 1375);
DISPLAY INVISIBLE (-6775 1375);
FORCEPROP 1 LAST PATH I69
J 0
(-6725 1525);
DISPLAY 0.978723 (-6725 1525);
PAINT WHITE (-6725 1525);
DISPLAY INVISIBLE (-6725 1525);
FORCEPROP 0 LAST ROOM PVDDQ_KLM
J 0
(-6725 1575);
DISPLAY 1.021277 (-6725 1575);
PAINT ORANGE (-6725 1575);
DISPLAY INVISIBLE (-6725 1575);
FORCEPROP 1 LASTPIN (-6775 1475) $PN 1
J 0
(-6765 1455);
DISPLAY 0.787234 (-6765 1455);
PAINT ORANGE (-6765 1455);
DISPLAY INVISIBLE (-6765 1455);
FORCEPROP 1 LASTPIN (-6775 1275) $PN 2
J 0
(-6765 1255);
DISPLAY 0.787234 (-6765 1255);
PAINT ORANGE (-6765 1255);
DISPLAY INVISIBLE (-6765 1255);
FORCEADD CAP_A..1
(-7100 1375);
FORCEPROP 1 LAST LOCATION C5G88
J 0
(-7050 1475);
DISPLAY 0.617021 (-7050 1475);
PAINT AQUA (-7050 1475);
FORCEPROP 1 LAST TOLERANCE 20%
J 0
(-7050 1325);
DISPLAY 0.617021 (-7050 1325);
PAINT SKYBLUE (-7050 1325);
FORCEPROP 1 LAST MATERIAL X6S
J 0
(-7050 1275);
DISPLAY 0.617021 (-7050 1275);
PAINT SKYBLUE (-7050 1275);
FORCEPROP 1 LAST PART_NUMBER E15431-004
J 0
(-7050 1225);
DISPLAY 0.617021 (-7050 1225);
PAINT BLUE (-7050 1225);
FORCEPROP 1 LAST VALUE 22.0UF
J 0
(-7050 1425);
DISPLAY 0.617021 (-7050 1425);
PAINT SKYBLUE (-7050 1425);
FORCEPROP 1 LAST VOLTAGE 4V
J 0
(-7050 1375);
DISPLAY 0.617021 (-7050 1375);
PAINT SKYBLUE (-7050 1375);
FORCEPROP 1 LAST PACK_TYPE 0603V
J 0
(-7050 1175);
DISPLAY 0.617021 (-7050 1175);
PAINT SKYBLUE (-7050 1175);
FORCEPROP 0 LAST SIDE_SKU 1S
J 0
(-7225 1425);
DISPLAY 1.021277 (-7225 1425);
PAINT ORANGE (-7225 1425);
FORCEPROP 2 LAST CDS_LIB dev_discrete
J 0
(-7100 1375);
PAINT MONO (-7100 1375);
DISPLAY INVISIBLE (-7100 1375);
FORCEPROP 1 LAST PATH I70
J 0
(-7050 1525);
DISPLAY 0.978723 (-7050 1525);
PAINT WHITE (-7050 1525);
DISPLAY INVISIBLE (-7050 1525);
FORCEPROP 0 LAST ROOM PVDDQ_KLM
J 0
(-7050 1575);
DISPLAY 1.021277 (-7050 1575);
PAINT ORANGE (-7050 1575);
DISPLAY INVISIBLE (-7050 1575);
FORCEPROP 1 LASTPIN (-7100 1475) $PN 1
J 0
(-7090 1455);
DISPLAY 0.787234 (-7090 1455);
PAINT ORANGE (-7090 1455);
DISPLAY INVISIBLE (-7090 1455);
FORCEPROP 1 LASTPIN (-7100 1275) $PN 2
J 0
(-7090 1255);
DISPLAY 0.787234 (-7090 1255);
PAINT ORANGE (-7090 1255);
DISPLAY INVISIBLE (-7090 1255);
FORCEADD CAP_A..1
(-1750 2575);
FORCEPROP 1 LAST LOCATION C5G103
J 0
(-1700 2675);
DISPLAY 0.617021 (-1700 2675);
PAINT AQUA (-1700 2675);
FORCEPROP 1 LAST PACK_TYPE 0603V
J 0
(-1700 2375);
DISPLAY 0.617021 (-1700 2375);
PAINT SKYBLUE (-1700 2375);
FORCEPROP 1 LAST MATERIAL X6S
J 0
(-1700 2475);
DISPLAY 0.617021 (-1700 2475);
PAINT SKYBLUE (-1700 2475);
FORCEPROP 1 LAST VOLTAGE 4V
J 0
(-1700 2575);
DISPLAY 0.617021 (-1700 2575);
PAINT SKYBLUE (-1700 2575);
FORCEPROP 1 LAST TOLERANCE 20%
J 0
(-1700 2525);
DISPLAY 0.617021 (-1700 2525);
PAINT SKYBLUE (-1700 2525);
FORCEPROP 1 LAST PART_NUMBER E15431-004
J 0
(-1700 2425);
DISPLAY 0.617021 (-1700 2425);
PAINT BLUE (-1700 2425);
FORCEPROP 1 LAST VALUE 22.0UF
J 0
(-1700 2625);
DISPLAY 0.617021 (-1700 2625);
PAINT SKYBLUE (-1700 2625);
FORCEPROP 0 LAST SIDE_SKU 1S
J 0
(-1875 2625);
DISPLAY 1.021277 (-1875 2625);
PAINT ORANGE (-1875 2625);
FORCEPROP 0 LAST ROOM PVDDQ_KLM
J 0
(-1700 2775);
DISPLAY 1.021277 (-1700 2775);
PAINT ORANGE (-1700 2775);
DISPLAY INVISIBLE (-1700 2775);
FORCEPROP 1 LAST PATH I71
J 0
(-1700 2725);
DISPLAY 0.978723 (-1700 2725);
PAINT WHITE (-1700 2725);
DISPLAY INVISIBLE (-1700 2725);
FORCEPROP 2 LAST CDS_LIB dev_discrete
J 0
(-1750 2575);
PAINT MONO (-1750 2575);
DISPLAY INVISIBLE (-1750 2575);
FORCEPROP 1 LASTPIN (-1750 2675) $PN 1
J 0
(-1740 2655);
DISPLAY 0.787234 (-1740 2655);
PAINT ORANGE (-1740 2655);
DISPLAY INVISIBLE (-1740 2655);
FORCEPROP 1 LASTPIN (-1750 2475) $PN 2
J 0
(-1740 2455);
DISPLAY 0.787234 (-1740 2455);
PAINT ORANGE (-1740 2455);
DISPLAY INVISIBLE (-1740 2455);
FORCEADD CAP_A..1
(-1450 2575);
FORCEPROP 1 LAST LOCATION C5G104
J 0
(-1400 2675);
DISPLAY 0.617021 (-1400 2675);
PAINT AQUA (-1400 2675);
FORCEPROP 1 LAST PACK_TYPE 0603V
J 0
(-1400 2375);
DISPLAY 0.617021 (-1400 2375);
PAINT SKYBLUE (-1400 2375);
FORCEPROP 1 LAST MATERIAL X6S
J 0
(-1400 2475);
DISPLAY 0.617021 (-1400 2475);
PAINT SKYBLUE (-1400 2475);
FORCEPROP 1 LAST VOLTAGE 4V
J 0
(-1400 2575);
DISPLAY 0.617021 (-1400 2575);
PAINT SKYBLUE (-1400 2575);
FORCEPROP 1 LAST TOLERANCE 20%
J 0
(-1400 2525);
DISPLAY 0.617021 (-1400 2525);
PAINT SKYBLUE (-1400 2525);
FORCEPROP 1 LAST PART_NUMBER E15431-004
J 0
(-1400 2425);
DISPLAY 0.617021 (-1400 2425);
PAINT BLUE (-1400 2425);
FORCEPROP 1 LAST VALUE 22.0UF
J 0
(-1400 2625);
DISPLAY 0.617021 (-1400 2625);
PAINT SKYBLUE (-1400 2625);
FORCEPROP 0 LAST SIDE_SKU 1S
J 0
(-1575 2625);
DISPLAY 1.021277 (-1575 2625);
PAINT ORANGE (-1575 2625);
FORCEPROP 0 LAST ROOM PVDDQ_KLM
J 0
(-1400 2775);
DISPLAY 1.021277 (-1400 2775);
PAINT ORANGE (-1400 2775);
DISPLAY INVISIBLE (-1400 2775);
FORCEPROP 1 LAST PATH I72
J 0
(-1400 2725);
DISPLAY 0.978723 (-1400 2725);
PAINT WHITE (-1400 2725);
DISPLAY INVISIBLE (-1400 2725);
FORCEPROP 2 LAST CDS_LIB dev_discrete
J 0
(-1450 2575);
PAINT MONO (-1450 2575);
DISPLAY INVISIBLE (-1450 2575);
FORCEPROP 1 LASTPIN (-1450 2675) $PN 1
J 0
(-1440 2655);
DISPLAY 0.787234 (-1440 2655);
PAINT ORANGE (-1440 2655);
DISPLAY INVISIBLE (-1440 2655);
FORCEPROP 1 LASTPIN (-1450 2475) $PN 2
J 0
(-1440 2455);
DISPLAY 0.787234 (-1440 2455);
PAINT ORANGE (-1440 2455);
DISPLAY INVISIBLE (-1440 2455);
FORCEADD CAP_A..1
(-1150 2575);
FORCEPROP 1 LAST LOCATION C5G105
J 0
(-1100 2675);
DISPLAY 0.617021 (-1100 2675);
PAINT AQUA (-1100 2675);
FORCEPROP 1 LAST PACK_TYPE 0603V
J 0
(-1100 2375);
DISPLAY 0.617021 (-1100 2375);
PAINT SKYBLUE (-1100 2375);
FORCEPROP 1 LAST MATERIAL X6S
J 0
(-1100 2475);
DISPLAY 0.617021 (-1100 2475);
PAINT SKYBLUE (-1100 2475);
FORCEPROP 1 LAST VOLTAGE 4V
J 0
(-1100 2575);
DISPLAY 0.617021 (-1100 2575);
PAINT SKYBLUE (-1100 2575);
FORCEPROP 1 LAST TOLERANCE 20%
J 0
(-1100 2525);
DISPLAY 0.617021 (-1100 2525);
PAINT SKYBLUE (-1100 2525);
FORCEPROP 1 LAST PART_NUMBER E15431-004
J 0
(-1100 2425);
DISPLAY 0.617021 (-1100 2425);
PAINT BLUE (-1100 2425);
FORCEPROP 1 LAST VALUE 22.0UF
J 0
(-1100 2625);
DISPLAY 0.617021 (-1100 2625);
PAINT SKYBLUE (-1100 2625);
FORCEPROP 0 LAST SIDE_SKU 1S
J 0
(-1275 2625);
DISPLAY 1.021277 (-1275 2625);
PAINT ORANGE (-1275 2625);
FORCEPROP 0 LAST ROOM PVDDQ_KLM
J 0
(-1100 2775);
DISPLAY 1.021277 (-1100 2775);
PAINT ORANGE (-1100 2775);
DISPLAY INVISIBLE (-1100 2775);
FORCEPROP 1 LAST PATH I73
J 0
(-1100 2725);
DISPLAY 0.978723 (-1100 2725);
PAINT WHITE (-1100 2725);
DISPLAY INVISIBLE (-1100 2725);
FORCEPROP 2 LAST CDS_LIB dev_discrete
J 0
(-1150 2575);
PAINT MONO (-1150 2575);
DISPLAY INVISIBLE (-1150 2575);
FORCEPROP 1 LASTPIN (-1150 2675) $PN 1
J 0
(-1140 2655);
DISPLAY 0.787234 (-1140 2655);
PAINT ORANGE (-1140 2655);
DISPLAY INVISIBLE (-1140 2655);
FORCEPROP 1 LASTPIN (-1150 2475) $PN 2
J 0
(-1140 2455);
DISPLAY 0.787234 (-1140 2455);
PAINT ORANGE (-1140 2455);
DISPLAY INVISIBLE (-1140 2455);
FORCEADD CAP_A..1
(-2050 2575);
FORCEPROP 1 LAST LOCATION C5G102
J 0
(-2000 2675);
DISPLAY 0.617021 (-2000 2675);
PAINT AQUA (-2000 2675);
FORCEPROP 1 LAST PACK_TYPE 0603V
J 0
(-2000 2375);
DISPLAY 0.617021 (-2000 2375);
PAINT SKYBLUE (-2000 2375);
FORCEPROP 1 LAST MATERIAL X6S
J 0
(-2000 2475);
DISPLAY 0.617021 (-2000 2475);
PAINT SKYBLUE (-2000 2475);
FORCEPROP 1 LAST VOLTAGE 4V
J 0
(-2000 2575);
DISPLAY 0.617021 (-2000 2575);
PAINT SKYBLUE (-2000 2575);
FORCEPROP 1 LAST TOLERANCE 20%
J 0
(-2000 2525);
DISPLAY 0.617021 (-2000 2525);
PAINT SKYBLUE (-2000 2525);
FORCEPROP 1 LAST PART_NUMBER E15431-004
J 0
(-2000 2425);
DISPLAY 0.617021 (-2000 2425);
PAINT BLUE (-2000 2425);
FORCEPROP 1 LAST VALUE 22.0UF
J 0
(-2000 2625);
DISPLAY 0.617021 (-2000 2625);
PAINT SKYBLUE (-2000 2625);
FORCEPROP 0 LAST SIDE_SKU 1S
J 0
(-2175 2625);
DISPLAY 1.021277 (-2175 2625);
PAINT ORANGE (-2175 2625);
FORCEPROP 0 LAST ROOM PVDDQ_KLM
J 0
(-2000 2775);
DISPLAY 1.021277 (-2000 2775);
PAINT ORANGE (-2000 2775);
DISPLAY INVISIBLE (-2000 2775);
FORCEPROP 1 LAST PATH I74
J 0
(-2000 2725);
DISPLAY 0.978723 (-2000 2725);
PAINT WHITE (-2000 2725);
DISPLAY INVISIBLE (-2000 2725);
FORCEPROP 2 LAST CDS_LIB dev_discrete
J 0
(-2050 2575);
PAINT MONO (-2050 2575);
DISPLAY INVISIBLE (-2050 2575);
FORCEPROP 1 LASTPIN (-2050 2675) $PN 1
J 0
(-2040 2655);
DISPLAY 0.787234 (-2040 2655);
PAINT ORANGE (-2040 2655);
DISPLAY INVISIBLE (-2040 2655);
FORCEPROP 1 LASTPIN (-2050 2475) $PN 2
J 0
(-2040 2455);
DISPLAY 0.787234 (-2040 2455);
PAINT ORANGE (-2040 2455);
DISPLAY INVISIBLE (-2040 2455);
FORCEADD CAP_A..1
(-2350 2575);
FORCEPROP 1 LAST LOCATION C5G101
J 0
(-2300 2675);
DISPLAY 0.617021 (-2300 2675);
PAINT AQUA (-2300 2675);
FORCEPROP 1 LAST PART_NUMBER E15431-004
J 0
(-2300 2425);
DISPLAY 0.617021 (-2300 2425);
PAINT BLUE (-2300 2425);
FORCEPROP 1 LAST TOLERANCE 20%
J 0
(-2300 2525);
DISPLAY 0.617021 (-2300 2525);
PAINT SKYBLUE (-2300 2525);
FORCEPROP 1 LAST VOLTAGE 4V
J 0
(-2300 2575);
DISPLAY 0.617021 (-2300 2575);
PAINT SKYBLUE (-2300 2575);
FORCEPROP 1 LAST MATERIAL X6S
J 0
(-2300 2475);
DISPLAY 0.617021 (-2300 2475);
PAINT SKYBLUE (-2300 2475);
FORCEPROP 1 LAST PACK_TYPE 0603V
J 0
(-2300 2375);
DISPLAY 0.617021 (-2300 2375);
PAINT SKYBLUE (-2300 2375);
FORCEPROP 1 LAST VALUE 22.0UF
J 0
(-2300 2625);
DISPLAY 0.617021 (-2300 2625);
PAINT SKYBLUE (-2300 2625);
FORCEPROP 0 LAST SIDE_SKU 1S
J 0
(-2475 2625);
DISPLAY 1.021277 (-2475 2625);
PAINT ORANGE (-2475 2625);
FORCEPROP 0 LAST ROOM PVDDQ_KLM
J 0
(-2300 2775);
DISPLAY 1.021277 (-2300 2775);
PAINT ORANGE (-2300 2775);
DISPLAY INVISIBLE (-2300 2775);
FORCEPROP 1 LAST PATH I75
J 0
(-2300 2725);
DISPLAY 0.978723 (-2300 2725);
PAINT WHITE (-2300 2725);
DISPLAY INVISIBLE (-2300 2725);
FORCEPROP 2 LAST CDS_LIB dev_discrete
J 0
(-2350 2575);
PAINT MONO (-2350 2575);
DISPLAY INVISIBLE (-2350 2575);
FORCEPROP 1 LASTPIN (-2350 2675) $PN 1
J 0
(-2340 2655);
DISPLAY 0.787234 (-2340 2655);
PAINT ORANGE (-2340 2655);
DISPLAY INVISIBLE (-2340 2655);
FORCEPROP 1 LASTPIN (-2350 2475) $PN 2
J 0
(-2340 2455);
DISPLAY 0.787234 (-2340 2455);
PAINT ORANGE (-2340 2455);
DISPLAY INVISIBLE (-2340 2455);
FORCEADD CAP_A..1
(-2650 2575);
FORCEPROP 1 LAST PACK_TYPE 0603V
J 0
(-2600 2375);
DISPLAY 0.617021 (-2600 2375);
PAINT SKYBLUE (-2600 2375);
FORCEPROP 1 LAST PART_NUMBER E15431-004
J 0
(-2600 2425);
DISPLAY 0.617021 (-2600 2425);
PAINT BLUE (-2600 2425);
FORCEPROP 1 LAST LOCATION C5G100
J 0
(-2600 2675);
DISPLAY 0.617021 (-2600 2675);
PAINT AQUA (-2600 2675);
FORCEPROP 1 LAST VALUE 22.0UF
J 0
(-2600 2625);
DISPLAY 0.617021 (-2600 2625);
PAINT SKYBLUE (-2600 2625);
FORCEPROP 1 LAST TOLERANCE 20%
J 0
(-2600 2525);
DISPLAY 0.617021 (-2600 2525);
PAINT SKYBLUE (-2600 2525);
FORCEPROP 1 LAST VOLTAGE 4V
J 0
(-2600 2575);
DISPLAY 0.617021 (-2600 2575);
PAINT SKYBLUE (-2600 2575);
FORCEPROP 1 LAST MATERIAL X6S
J 0
(-2600 2475);
DISPLAY 0.617021 (-2600 2475);
PAINT SKYBLUE (-2600 2475);
FORCEPROP 0 LAST SIDE_SKU 1S
J 0
(-2775 2625);
DISPLAY 1.021277 (-2775 2625);
PAINT ORANGE (-2775 2625);
FORCEPROP 0 LAST ROOM PVDDQ_KLM
J 0
(-2600 2775);
DISPLAY 1.021277 (-2600 2775);
PAINT ORANGE (-2600 2775);
DISPLAY INVISIBLE (-2600 2775);
FORCEPROP 1 LAST PATH I76
J 0
(-2600 2725);
DISPLAY 0.978723 (-2600 2725);
PAINT WHITE (-2600 2725);
DISPLAY INVISIBLE (-2600 2725);
FORCEPROP 2 LAST CDS_LIB dev_discrete
J 0
(-2650 2575);
PAINT MONO (-2650 2575);
DISPLAY INVISIBLE (-2650 2575);
FORCEPROP 1 LASTPIN (-2650 2675) $PN 1
J 0
(-2640 2655);
DISPLAY 0.787234 (-2640 2655);
PAINT ORANGE (-2640 2655);
DISPLAY INVISIBLE (-2640 2655);
FORCEPROP 1 LASTPIN (-2650 2475) $PN 2
J 0
(-2640 2455);
DISPLAY 0.787234 (-2640 2455);
PAINT ORANGE (-2640 2455);
DISPLAY INVISIBLE (-2640 2455);
FORCEADD CAP_A..1
(-3000 2575);
FORCEPROP 1 LAST LOCATION C5G99
J 0
(-2950 2675);
DISPLAY 0.617021 (-2950 2675);
PAINT AQUA (-2950 2675);
FORCEPROP 1 LAST PACK_TYPE 0603V
J 0
(-2950 2375);
DISPLAY 0.617021 (-2950 2375);
PAINT SKYBLUE (-2950 2375);
FORCEPROP 1 LAST MATERIAL X6S
J 0
(-2950 2475);
DISPLAY 0.617021 (-2950 2475);
PAINT SKYBLUE (-2950 2475);
FORCEPROP 1 LAST VOLTAGE 4V
J 0
(-2950 2575);
DISPLAY 0.617021 (-2950 2575);
PAINT SKYBLUE (-2950 2575);
FORCEPROP 1 LAST TOLERANCE 20%
J 0
(-2950 2525);
DISPLAY 0.617021 (-2950 2525);
PAINT SKYBLUE (-2950 2525);
FORCEPROP 1 LAST PART_NUMBER E15431-004
J 0
(-2950 2425);
DISPLAY 0.617021 (-2950 2425);
PAINT BLUE (-2950 2425);
FORCEPROP 1 LAST VALUE 22.0UF
J 0
(-2950 2625);
DISPLAY 0.617021 (-2950 2625);
PAINT SKYBLUE (-2950 2625);
FORCEPROP 0 LAST SIDE_SKU 1S
J 0
(-3125 2625);
DISPLAY 1.021277 (-3125 2625);
PAINT ORANGE (-3125 2625);
FORCEPROP 0 LAST ROOM PVDDQ_KLM
J 0
(-2950 2775);
DISPLAY 1.021277 (-2950 2775);
PAINT ORANGE (-2950 2775);
DISPLAY INVISIBLE (-2950 2775);
FORCEPROP 1 LAST PATH I77
J 0
(-2950 2725);
DISPLAY 0.978723 (-2950 2725);
PAINT WHITE (-2950 2725);
DISPLAY INVISIBLE (-2950 2725);
FORCEPROP 2 LAST CDS_LIB dev_discrete
J 0
(-3000 2575);
PAINT MONO (-3000 2575);
DISPLAY INVISIBLE (-3000 2575);
FORCEPROP 1 LASTPIN (-3000 2675) $PN 1
J 0
(-2990 2655);
DISPLAY 0.787234 (-2990 2655);
PAINT ORANGE (-2990 2655);
DISPLAY INVISIBLE (-2990 2655);
FORCEPROP 1 LASTPIN (-3000 2475) $PN 2
J 0
(-2990 2455);
DISPLAY 0.787234 (-2990 2455);
PAINT ORANGE (-2990 2455);
DISPLAY INVISIBLE (-2990 2455);
FORCEADD CAP_A..1
(-3300 2575);
FORCEPROP 1 LAST LOCATION C5G98
J 0
(-3250 2675);
DISPLAY 0.617021 (-3250 2675);
PAINT AQUA (-3250 2675);
FORCEPROP 1 LAST PACK_TYPE 0603V
J 0
(-3250 2375);
DISPLAY 0.617021 (-3250 2375);
PAINT SKYBLUE (-3250 2375);
FORCEPROP 1 LAST MATERIAL X6S
J 0
(-3250 2475);
DISPLAY 0.617021 (-3250 2475);
PAINT SKYBLUE (-3250 2475);
FORCEPROP 1 LAST VOLTAGE 4V
J 0
(-3250 2575);
DISPLAY 0.617021 (-3250 2575);
PAINT SKYBLUE (-3250 2575);
FORCEPROP 1 LAST TOLERANCE 20%
J 0
(-3250 2525);
DISPLAY 0.617021 (-3250 2525);
PAINT SKYBLUE (-3250 2525);
FORCEPROP 1 LAST PART_NUMBER E15431-004
J 0
(-3250 2425);
DISPLAY 0.617021 (-3250 2425);
PAINT BLUE (-3250 2425);
FORCEPROP 1 LAST VALUE 22.0UF
J 0
(-3250 2625);
DISPLAY 0.617021 (-3250 2625);
PAINT SKYBLUE (-3250 2625);
FORCEPROP 0 LAST SIDE_SKU 1S
J 0
(-3425 2625);
DISPLAY 1.021277 (-3425 2625);
PAINT ORANGE (-3425 2625);
FORCEPROP 0 LAST ROOM PVDDQ_KLM
J 0
(-3250 2775);
DISPLAY 1.021277 (-3250 2775);
PAINT ORANGE (-3250 2775);
DISPLAY INVISIBLE (-3250 2775);
FORCEPROP 1 LAST PATH I78
J 0
(-3250 2725);
DISPLAY 0.978723 (-3250 2725);
PAINT WHITE (-3250 2725);
DISPLAY INVISIBLE (-3250 2725);
FORCEPROP 2 LAST CDS_LIB dev_discrete
J 0
(-3300 2575);
PAINT MONO (-3300 2575);
DISPLAY INVISIBLE (-3300 2575);
FORCEPROP 1 LASTPIN (-3300 2675) $PN 1
J 0
(-3290 2655);
DISPLAY 0.787234 (-3290 2655);
PAINT ORANGE (-3290 2655);
DISPLAY INVISIBLE (-3290 2655);
FORCEPROP 1 LASTPIN (-3300 2475) $PN 2
J 0
(-3290 2455);
DISPLAY 0.787234 (-3290 2455);
PAINT ORANGE (-3290 2455);
DISPLAY INVISIBLE (-3290 2455);
FORCEADD CAP_A..1
(-3600 2575);
FORCEPROP 1 LAST LOCATION C5G97
J 0
(-3550 2675);
DISPLAY 0.617021 (-3550 2675);
PAINT AQUA (-3550 2675);
FORCEPROP 1 LAST VALUE 22.0UF
J 0
(-3550 2625);
DISPLAY 0.617021 (-3550 2625);
PAINT SKYBLUE (-3550 2625);
FORCEPROP 1 LAST PART_NUMBER E15431-004
J 0
(-3550 2425);
DISPLAY 0.617021 (-3550 2425);
PAINT BLUE (-3550 2425);
FORCEPROP 1 LAST TOLERANCE 20%
J 0
(-3550 2525);
DISPLAY 0.617021 (-3550 2525);
PAINT SKYBLUE (-3550 2525);
FORCEPROP 1 LAST VOLTAGE 4V
J 0
(-3550 2575);
DISPLAY 0.617021 (-3550 2575);
PAINT SKYBLUE (-3550 2575);
FORCEPROP 1 LAST MATERIAL X6S
J 0
(-3550 2475);
DISPLAY 0.617021 (-3550 2475);
PAINT SKYBLUE (-3550 2475);
FORCEPROP 1 LAST PACK_TYPE 0603V
J 0
(-3550 2375);
DISPLAY 0.617021 (-3550 2375);
PAINT SKYBLUE (-3550 2375);
FORCEPROP 0 LAST SIDE_SKU 1S
J 0
(-3725 2625);
DISPLAY 1.021277 (-3725 2625);
PAINT ORANGE (-3725 2625);
FORCEPROP 0 LAST ROOM PVDDQ_KLM
J 0
(-3550 2775);
DISPLAY 1.021277 (-3550 2775);
PAINT ORANGE (-3550 2775);
DISPLAY INVISIBLE (-3550 2775);
FORCEPROP 1 LAST PATH I79
J 0
(-3550 2725);
DISPLAY 0.978723 (-3550 2725);
PAINT WHITE (-3550 2725);
DISPLAY INVISIBLE (-3550 2725);
FORCEPROP 2 LAST CDS_LIB dev_discrete
J 0
(-3600 2575);
PAINT MONO (-3600 2575);
DISPLAY INVISIBLE (-3600 2575);
FORCEPROP 1 LASTPIN (-3600 2675) $PN 1
J 0
(-3590 2655);
DISPLAY 0.787234 (-3590 2655);
PAINT ORANGE (-3590 2655);
DISPLAY INVISIBLE (-3590 2655);
FORCEPROP 1 LASTPIN (-3600 2475) $PN 2
J 0
(-3590 2455);
DISPLAY 0.787234 (-3590 2455);
PAINT ORANGE (-3590 2455);
DISPLAY INVISIBLE (-3590 2455);
FORCEADD PVDDQ_GHJ..1
(-7125 2825);
FORCEPROP 3 LASTPIN (-7125 2775) SIG_NAME PVDDQ_GHJ\g
J 0
(-7115 2785);
DISPLAY 0.659574 (-7115 2785);
PAINT MONO (-7115 2785);
DISPLAY INVISIBLE (-7115 2785);
FORCEPROP 2 LAST CDS_LIB mstr_symbols
J 0
(-7125 2825);
PAINT MONO (-7125 2825);
DISPLAY INVISIBLE (-7125 2825);
FORCEPROP 1 LAST VOLTAGE 1.2V
J 0
(-7170 2782);
DISPLAY 0.340426 (-7170 2782);
PAINT SKYBLUE (-7170 2782);
DISPLAY INVISIBLE (-7170 2782);
FORCEPROP 1 LAST PATH I8
J 0
(-7075 2850);
DISPLAY 0.872340 (-7075 2850);
PAINT AQUA (-7075 2850);
DISPLAY INVISIBLE (-7075 2850);
FORCEPROP 1 LAST BODY_TYPE PLUMBING
J 0
(-7170 2782);
DISPLAY 0.340426 (-7170 2782);
PAINT GREEN (-7170 2782);
DISPLAY INVISIBLE (-7170 2782);
FORCEPROP 1 LAST HDL_POWER PVDDQ_GHJ
J 1
(-7125 2875);
DISPLAY 0.872340 (-7125 2875);
PAINT GREEN (-7125 2875);
DISPLAY INVISIBLE (-7125 2875);
FORCEADD CAP_A..1
(-1150 1475);
FORCEPROP 1 LAST LOCATION C5G114
J 0
(-1100 1575);
DISPLAY 0.617021 (-1100 1575);
PAINT AQUA (-1100 1575);
FORCEPROP 1 LAST VALUE 22.0UF
J 0
(-1100 1525);
DISPLAY 0.617021 (-1100 1525);
PAINT SKYBLUE (-1100 1525);
FORCEPROP 1 LAST PART_NUMBER E15431-004
J 0
(-1100 1325);
DISPLAY 0.617021 (-1100 1325);
PAINT BLUE (-1100 1325);
FORCEPROP 1 LAST TOLERANCE 20%
J 0
(-1100 1425);
DISPLAY 0.617021 (-1100 1425);
PAINT SKYBLUE (-1100 1425);
FORCEPROP 1 LAST VOLTAGE 4V
J 0
(-1100 1475);
DISPLAY 0.617021 (-1100 1475);
PAINT SKYBLUE (-1100 1475);
FORCEPROP 1 LAST MATERIAL X6S
J 0
(-1100 1375);
DISPLAY 0.617021 (-1100 1375);
PAINT SKYBLUE (-1100 1375);
FORCEPROP 1 LAST PACK_TYPE 0603V
J 0
(-1100 1275);
DISPLAY 0.617021 (-1100 1275);
PAINT SKYBLUE (-1100 1275);
FORCEPROP 0 LAST SIDE_SKU 1S
J 0
(-1275 1525);
DISPLAY 1.021277 (-1275 1525);
PAINT ORANGE (-1275 1525);
FORCEPROP 2 LAST CDS_LIB dev_discrete
J 0
(-1150 1475);
PAINT MONO (-1150 1475);
DISPLAY INVISIBLE (-1150 1475);
FORCEPROP 1 LAST PATH I80
J 0
(-1100 1625);
DISPLAY 0.978723 (-1100 1625);
PAINT WHITE (-1100 1625);
DISPLAY INVISIBLE (-1100 1625);
FORCEPROP 0 LAST ROOM PVDDQ_KLM
J 0
(-1100 1675);
DISPLAY 1.021277 (-1100 1675);
PAINT ORANGE (-1100 1675);
DISPLAY INVISIBLE (-1100 1675);
FORCEPROP 1 LASTPIN (-1150 1575) $PN 1
J 0
(-1140 1555);
DISPLAY 0.787234 (-1140 1555);
PAINT ORANGE (-1140 1555);
DISPLAY INVISIBLE (-1140 1555);
FORCEPROP 1 LASTPIN (-1150 1375) $PN 2
J 0
(-1140 1355);
DISPLAY 0.787234 (-1140 1355);
PAINT ORANGE (-1140 1355);
DISPLAY INVISIBLE (-1140 1355);
FORCEADD CAP_A..1
(-1450 1475);
FORCEPROP 1 LAST LOCATION C5G113
J 0
(-1400 1575);
DISPLAY 0.617021 (-1400 1575);
PAINT AQUA (-1400 1575);
FORCEPROP 1 LAST VALUE 22.0UF
J 0
(-1400 1525);
DISPLAY 0.617021 (-1400 1525);
PAINT SKYBLUE (-1400 1525);
FORCEPROP 1 LAST PART_NUMBER E15431-004
J 0
(-1400 1325);
DISPLAY 0.617021 (-1400 1325);
PAINT BLUE (-1400 1325);
FORCEPROP 1 LAST TOLERANCE 20%
J 0
(-1400 1425);
DISPLAY 0.617021 (-1400 1425);
PAINT SKYBLUE (-1400 1425);
FORCEPROP 1 LAST VOLTAGE 4V
J 0
(-1400 1475);
DISPLAY 0.617021 (-1400 1475);
PAINT SKYBLUE (-1400 1475);
FORCEPROP 1 LAST MATERIAL X6S
J 0
(-1400 1375);
DISPLAY 0.617021 (-1400 1375);
PAINT SKYBLUE (-1400 1375);
FORCEPROP 1 LAST PACK_TYPE 0603V
J 0
(-1400 1275);
DISPLAY 0.617021 (-1400 1275);
PAINT SKYBLUE (-1400 1275);
FORCEPROP 0 LAST SIDE_SKU 1S
J 0
(-1575 1525);
DISPLAY 1.021277 (-1575 1525);
PAINT ORANGE (-1575 1525);
FORCEPROP 2 LAST CDS_LIB dev_discrete
J 0
(-1450 1475);
PAINT MONO (-1450 1475);
DISPLAY INVISIBLE (-1450 1475);
FORCEPROP 1 LAST PATH I81
J 0
(-1400 1625);
DISPLAY 0.978723 (-1400 1625);
PAINT WHITE (-1400 1625);
DISPLAY INVISIBLE (-1400 1625);
FORCEPROP 0 LAST ROOM PVDDQ_KLM
J 0
(-1400 1675);
DISPLAY 1.021277 (-1400 1675);
PAINT ORANGE (-1400 1675);
DISPLAY INVISIBLE (-1400 1675);
FORCEPROP 1 LASTPIN (-1450 1575) $PN 1
J 0
(-1440 1555);
DISPLAY 0.787234 (-1440 1555);
PAINT ORANGE (-1440 1555);
DISPLAY INVISIBLE (-1440 1555);
FORCEPROP 1 LASTPIN (-1450 1375) $PN 2
J 0
(-1440 1355);
DISPLAY 0.787234 (-1440 1355);
PAINT ORANGE (-1440 1355);
DISPLAY INVISIBLE (-1440 1355);
FORCEADD CAP_A..1
(-1750 1475);
FORCEPROP 1 LAST LOCATION C5G112
J 0
(-1700 1575);
DISPLAY 0.617021 (-1700 1575);
PAINT AQUA (-1700 1575);
FORCEPROP 1 LAST VALUE 22.0UF
J 0
(-1700 1525);
DISPLAY 0.617021 (-1700 1525);
PAINT SKYBLUE (-1700 1525);
FORCEPROP 1 LAST PART_NUMBER E15431-004
J 0
(-1700 1325);
DISPLAY 0.617021 (-1700 1325);
PAINT BLUE (-1700 1325);
FORCEPROP 1 LAST TOLERANCE 20%
J 0
(-1700 1425);
DISPLAY 0.617021 (-1700 1425);
PAINT SKYBLUE (-1700 1425);
FORCEPROP 1 LAST VOLTAGE 4V
J 0
(-1700 1475);
DISPLAY 0.617021 (-1700 1475);
PAINT SKYBLUE (-1700 1475);
FORCEPROP 1 LAST MATERIAL X6S
J 0
(-1700 1375);
DISPLAY 0.617021 (-1700 1375);
PAINT SKYBLUE (-1700 1375);
FORCEPROP 1 LAST PACK_TYPE 0603V
J 0
(-1700 1275);
DISPLAY 0.617021 (-1700 1275);
PAINT SKYBLUE (-1700 1275);
FORCEPROP 0 LAST SIDE_SKU 1S
J 0
(-1875 1525);
DISPLAY 1.021277 (-1875 1525);
PAINT ORANGE (-1875 1525);
FORCEPROP 2 LAST CDS_LIB dev_discrete
J 0
(-1750 1475);
PAINT MONO (-1750 1475);
DISPLAY INVISIBLE (-1750 1475);
FORCEPROP 1 LAST PATH I82
J 0
(-1700 1625);
DISPLAY 0.978723 (-1700 1625);
PAINT WHITE (-1700 1625);
DISPLAY INVISIBLE (-1700 1625);
FORCEPROP 0 LAST ROOM PVDDQ_KLM
J 0
(-1700 1675);
DISPLAY 1.021277 (-1700 1675);
PAINT ORANGE (-1700 1675);
DISPLAY INVISIBLE (-1700 1675);
FORCEPROP 1 LASTPIN (-1750 1575) $PN 1
J 0
(-1740 1555);
DISPLAY 0.787234 (-1740 1555);
PAINT ORANGE (-1740 1555);
DISPLAY INVISIBLE (-1740 1555);
FORCEPROP 1 LASTPIN (-1750 1375) $PN 2
J 0
(-1740 1355);
DISPLAY 0.787234 (-1740 1355);
PAINT ORANGE (-1740 1355);
DISPLAY INVISIBLE (-1740 1355);
FORCEADD CAP_A..1
(-2050 1475);
FORCEPROP 1 LAST LOCATION C5G111
J 0
(-2000 1575);
DISPLAY 0.617021 (-2000 1575);
PAINT AQUA (-2000 1575);
FORCEPROP 1 LAST VALUE 22.0UF
J 0
(-2000 1525);
DISPLAY 0.617021 (-2000 1525);
PAINT SKYBLUE (-2000 1525);
FORCEPROP 1 LAST PART_NUMBER E15431-004
J 0
(-2000 1325);
DISPLAY 0.617021 (-2000 1325);
PAINT BLUE (-2000 1325);
FORCEPROP 1 LAST TOLERANCE 20%
J 0
(-2000 1425);
DISPLAY 0.617021 (-2000 1425);
PAINT SKYBLUE (-2000 1425);
FORCEPROP 1 LAST VOLTAGE 4V
J 0
(-2000 1475);
DISPLAY 0.617021 (-2000 1475);
PAINT SKYBLUE (-2000 1475);
FORCEPROP 1 LAST MATERIAL X6S
J 0
(-2000 1375);
DISPLAY 0.617021 (-2000 1375);
PAINT SKYBLUE (-2000 1375);
FORCEPROP 1 LAST PACK_TYPE 0603V
J 0
(-2000 1275);
DISPLAY 0.617021 (-2000 1275);
PAINT SKYBLUE (-2000 1275);
FORCEPROP 0 LAST SIDE_SKU 1S
J 0
(-2175 1525);
DISPLAY 1.021277 (-2175 1525);
PAINT ORANGE (-2175 1525);
FORCEPROP 2 LAST CDS_LIB dev_discrete
J 0
(-2050 1475);
PAINT MONO (-2050 1475);
DISPLAY INVISIBLE (-2050 1475);
FORCEPROP 1 LAST PATH I83
J 0
(-2000 1625);
DISPLAY 0.978723 (-2000 1625);
PAINT WHITE (-2000 1625);
DISPLAY INVISIBLE (-2000 1625);
FORCEPROP 0 LAST ROOM PVDDQ_KLM
J 0
(-2000 1675);
DISPLAY 1.021277 (-2000 1675);
PAINT ORANGE (-2000 1675);
DISPLAY INVISIBLE (-2000 1675);
FORCEPROP 1 LASTPIN (-2050 1575) $PN 1
J 0
(-2040 1555);
DISPLAY 0.787234 (-2040 1555);
PAINT ORANGE (-2040 1555);
DISPLAY INVISIBLE (-2040 1555);
FORCEPROP 1 LASTPIN (-2050 1375) $PN 2
J 0
(-2040 1355);
DISPLAY 0.787234 (-2040 1355);
PAINT ORANGE (-2040 1355);
DISPLAY INVISIBLE (-2040 1355);
FORCEADD CAP_A..1
(-2350 1475);
FORCEPROP 1 LAST LOCATION C5G110
J 0
(-2300 1575);
DISPLAY 0.617021 (-2300 1575);
PAINT AQUA (-2300 1575);
FORCEPROP 1 LAST VOLTAGE 4V
J 0
(-2300 1475);
DISPLAY 0.617021 (-2300 1475);
PAINT SKYBLUE (-2300 1475);
FORCEPROP 1 LAST PACK_TYPE 0603V
J 0
(-2300 1275);
DISPLAY 0.617021 (-2300 1275);
PAINT SKYBLUE (-2300 1275);
FORCEPROP 1 LAST MATERIAL X6S
J 0
(-2300 1375);
DISPLAY 0.617021 (-2300 1375);
PAINT SKYBLUE (-2300 1375);
FORCEPROP 1 LAST TOLERANCE 20%
J 0
(-2300 1425);
DISPLAY 0.617021 (-2300 1425);
PAINT SKYBLUE (-2300 1425);
FORCEPROP 1 LAST PART_NUMBER E15431-004
J 0
(-2300 1325);
DISPLAY 0.617021 (-2300 1325);
PAINT BLUE (-2300 1325);
FORCEPROP 1 LAST VALUE 22.0UF
J 0
(-2300 1525);
DISPLAY 0.617021 (-2300 1525);
PAINT SKYBLUE (-2300 1525);
FORCEPROP 0 LAST SIDE_SKU 1S
J 0
(-2475 1525);
DISPLAY 1.021277 (-2475 1525);
PAINT ORANGE (-2475 1525);
FORCEPROP 2 LAST CDS_LIB dev_discrete
J 0
(-2350 1475);
PAINT MONO (-2350 1475);
DISPLAY INVISIBLE (-2350 1475);
FORCEPROP 1 LAST PATH I84
J 0
(-2300 1625);
DISPLAY 0.978723 (-2300 1625);
PAINT WHITE (-2300 1625);
DISPLAY INVISIBLE (-2300 1625);
FORCEPROP 0 LAST ROOM PVDDQ_KLM
J 0
(-2300 1675);
DISPLAY 1.021277 (-2300 1675);
PAINT ORANGE (-2300 1675);
DISPLAY INVISIBLE (-2300 1675);
FORCEPROP 1 LASTPIN (-2350 1575) $PN 1
J 0
(-2340 1555);
DISPLAY 0.787234 (-2340 1555);
PAINT ORANGE (-2340 1555);
DISPLAY INVISIBLE (-2340 1555);
FORCEPROP 1 LASTPIN (-2350 1375) $PN 2
J 0
(-2340 1355);
DISPLAY 0.787234 (-2340 1355);
PAINT ORANGE (-2340 1355);
DISPLAY INVISIBLE (-2340 1355);
FORCEADD CAP_A..1
(-2650 1475);
FORCEPROP 1 LAST PACK_TYPE 0603V
J 0
(-2600 1275);
DISPLAY 0.617021 (-2600 1275);
PAINT SKYBLUE (-2600 1275);
FORCEPROP 1 LAST PART_NUMBER E15431-004
J 0
(-2600 1325);
DISPLAY 0.617021 (-2600 1325);
PAINT BLUE (-2600 1325);
FORCEPROP 1 LAST LOCATION C5G109
J 0
(-2600 1575);
DISPLAY 0.617021 (-2600 1575);
PAINT AQUA (-2600 1575);
FORCEPROP 1 LAST VOLTAGE 4V
J 0
(-2600 1475);
DISPLAY 0.617021 (-2600 1475);
PAINT SKYBLUE (-2600 1475);
FORCEPROP 1 LAST VALUE 22.0UF
J 0
(-2600 1525);
DISPLAY 0.617021 (-2600 1525);
PAINT SKYBLUE (-2600 1525);
FORCEPROP 1 LAST MATERIAL X6S
J 0
(-2600 1375);
DISPLAY 0.617021 (-2600 1375);
PAINT SKYBLUE (-2600 1375);
FORCEPROP 1 LAST TOLERANCE 20%
J 0
(-2600 1425);
DISPLAY 0.617021 (-2600 1425);
PAINT SKYBLUE (-2600 1425);
FORCEPROP 0 LAST SIDE_SKU 1S
J 0
(-2775 1525);
DISPLAY 1.021277 (-2775 1525);
PAINT ORANGE (-2775 1525);
FORCEPROP 2 LAST CDS_LIB dev_discrete
J 0
(-2650 1475);
PAINT MONO (-2650 1475);
DISPLAY INVISIBLE (-2650 1475);
FORCEPROP 1 LAST PATH I85
J 0
(-2600 1625);
DISPLAY 0.978723 (-2600 1625);
PAINT WHITE (-2600 1625);
DISPLAY INVISIBLE (-2600 1625);
FORCEPROP 0 LAST ROOM PVDDQ_KLM
J 0
(-2600 1675);
DISPLAY 1.021277 (-2600 1675);
PAINT ORANGE (-2600 1675);
DISPLAY INVISIBLE (-2600 1675);
FORCEPROP 1 LASTPIN (-2650 1575) $PN 1
J 0
(-2640 1555);
DISPLAY 0.787234 (-2640 1555);
PAINT ORANGE (-2640 1555);
DISPLAY INVISIBLE (-2640 1555);
FORCEPROP 1 LASTPIN (-2650 1375) $PN 2
J 0
(-2640 1355);
DISPLAY 0.787234 (-2640 1355);
PAINT ORANGE (-2640 1355);
DISPLAY INVISIBLE (-2640 1355);
FORCEADD CAP_A..1
(-3000 1475);
FORCEPROP 1 LAST LOCATION C5G108
J 0
(-2950 1575);
DISPLAY 0.617021 (-2950 1575);
PAINT AQUA (-2950 1575);
FORCEPROP 1 LAST MATERIAL X6S
J 0
(-2950 1375);
DISPLAY 0.617021 (-2950 1375);
PAINT SKYBLUE (-2950 1375);
FORCEPROP 1 LAST VALUE 22.0UF
J 0
(-2950 1525);
DISPLAY 0.617021 (-2950 1525);
PAINT SKYBLUE (-2950 1525);
FORCEPROP 1 LAST PART_NUMBER E15431-004
J 0
(-2950 1325);
DISPLAY 0.617021 (-2950 1325);
PAINT BLUE (-2950 1325);
FORCEPROP 1 LAST TOLERANCE 20%
J 0
(-2950 1425);
DISPLAY 0.617021 (-2950 1425);
PAINT SKYBLUE (-2950 1425);
FORCEPROP 1 LAST VOLTAGE 4V
J 0
(-2950 1475);
DISPLAY 0.617021 (-2950 1475);
PAINT SKYBLUE (-2950 1475);
FORCEPROP 1 LAST PACK_TYPE 0603V
J 0
(-2950 1275);
DISPLAY 0.617021 (-2950 1275);
PAINT SKYBLUE (-2950 1275);
FORCEPROP 0 LAST SIDE_SKU 1S
J 0
(-3125 1525);
DISPLAY 1.021277 (-3125 1525);
PAINT ORANGE (-3125 1525);
FORCEPROP 2 LAST CDS_LIB dev_discrete
J 0
(-3000 1475);
PAINT MONO (-3000 1475);
DISPLAY INVISIBLE (-3000 1475);
FORCEPROP 1 LAST PATH I86
J 0
(-2950 1625);
DISPLAY 0.978723 (-2950 1625);
PAINT WHITE (-2950 1625);
DISPLAY INVISIBLE (-2950 1625);
FORCEPROP 0 LAST ROOM PVDDQ_KLM
J 0
(-2950 1675);
DISPLAY 1.021277 (-2950 1675);
PAINT ORANGE (-2950 1675);
DISPLAY INVISIBLE (-2950 1675);
FORCEPROP 1 LASTPIN (-3000 1575) $PN 1
J 0
(-2990 1555);
DISPLAY 0.787234 (-2990 1555);
PAINT ORANGE (-2990 1555);
DISPLAY INVISIBLE (-2990 1555);
FORCEPROP 1 LASTPIN (-3000 1375) $PN 2
J 0
(-2990 1355);
DISPLAY 0.787234 (-2990 1355);
PAINT ORANGE (-2990 1355);
DISPLAY INVISIBLE (-2990 1355);
FORCEADD CAP_A..1
(-3300 1475);
FORCEPROP 1 LAST LOCATION C5G107
J 0
(-3250 1575);
DISPLAY 0.617021 (-3250 1575);
PAINT AQUA (-3250 1575);
FORCEPROP 1 LAST TOLERANCE 20%
J 0
(-3250 1425);
DISPLAY 0.617021 (-3250 1425);
PAINT SKYBLUE (-3250 1425);
FORCEPROP 1 LAST MATERIAL X6S
J 0
(-3250 1375);
DISPLAY 0.617021 (-3250 1375);
PAINT SKYBLUE (-3250 1375);
FORCEPROP 1 LAST VALUE 22.0UF
J 0
(-3250 1525);
DISPLAY 0.617021 (-3250 1525);
PAINT SKYBLUE (-3250 1525);
FORCEPROP 1 LAST PART_NUMBER E15431-004
J 0
(-3250 1325);
DISPLAY 0.617021 (-3250 1325);
PAINT BLUE (-3250 1325);
FORCEPROP 1 LAST VOLTAGE 4V
J 0
(-3250 1475);
DISPLAY 0.617021 (-3250 1475);
PAINT SKYBLUE (-3250 1475);
FORCEPROP 1 LAST PACK_TYPE 0603V
J 0
(-3250 1275);
DISPLAY 0.617021 (-3250 1275);
PAINT SKYBLUE (-3250 1275);
FORCEPROP 0 LAST SIDE_SKU 1S
J 0
(-3425 1525);
DISPLAY 1.021277 (-3425 1525);
PAINT ORANGE (-3425 1525);
FORCEPROP 2 LAST CDS_LIB dev_discrete
J 0
(-3300 1475);
PAINT MONO (-3300 1475);
DISPLAY INVISIBLE (-3300 1475);
FORCEPROP 1 LAST PATH I87
J 0
(-3250 1625);
DISPLAY 0.978723 (-3250 1625);
PAINT WHITE (-3250 1625);
DISPLAY INVISIBLE (-3250 1625);
FORCEPROP 0 LAST ROOM PVDDQ_KLM
J 0
(-3250 1675);
DISPLAY 1.021277 (-3250 1675);
PAINT ORANGE (-3250 1675);
DISPLAY INVISIBLE (-3250 1675);
FORCEPROP 1 LASTPIN (-3300 1575) $PN 1
J 0
(-3290 1555);
DISPLAY 0.787234 (-3290 1555);
PAINT ORANGE (-3290 1555);
DISPLAY INVISIBLE (-3290 1555);
FORCEPROP 1 LASTPIN (-3300 1375) $PN 2
J 0
(-3290 1355);
DISPLAY 0.787234 (-3290 1355);
PAINT ORANGE (-3290 1355);
DISPLAY INVISIBLE (-3290 1355);
FORCEADD CAP_A..1
(-3600 1475);
FORCEPROP 1 LAST LOCATION C5G106
J 0
(-3550 1575);
DISPLAY 0.617021 (-3550 1575);
PAINT AQUA (-3550 1575);
FORCEPROP 1 LAST VALUE 22.0UF
J 0
(-3550 1525);
DISPLAY 0.617021 (-3550 1525);
PAINT SKYBLUE (-3550 1525);
FORCEPROP 1 LAST VOLTAGE 4V
J 0
(-3550 1475);
DISPLAY 0.617021 (-3550 1475);
PAINT SKYBLUE (-3550 1475);
FORCEPROP 1 LAST TOLERANCE 20%
J 0
(-3550 1425);
DISPLAY 0.617021 (-3550 1425);
PAINT SKYBLUE (-3550 1425);
FORCEPROP 1 LAST PACK_TYPE 0603V
J 0
(-3550 1275);
DISPLAY 0.617021 (-3550 1275);
PAINT SKYBLUE (-3550 1275);
FORCEPROP 1 LAST MATERIAL X6S
J 0
(-3550 1375);
DISPLAY 0.617021 (-3550 1375);
PAINT SKYBLUE (-3550 1375);
FORCEPROP 1 LAST PART_NUMBER E15431-004
J 0
(-3550 1325);
DISPLAY 0.617021 (-3550 1325);
PAINT BLUE (-3550 1325);
FORCEPROP 0 LAST SIDE_SKU 1S
J 0
(-3725 1525);
DISPLAY 1.021277 (-3725 1525);
PAINT ORANGE (-3725 1525);
FORCEPROP 2 LAST CDS_LIB dev_discrete
J 0
(-3600 1475);
PAINT MONO (-3600 1475);
DISPLAY INVISIBLE (-3600 1475);
FORCEPROP 1 LAST PATH I88
J 0
(-3550 1625);
DISPLAY 0.978723 (-3550 1625);
PAINT WHITE (-3550 1625);
DISPLAY INVISIBLE (-3550 1625);
FORCEPROP 0 LAST ROOM PVDDQ_KLM
J 0
(-3550 1675);
DISPLAY 1.021277 (-3550 1675);
PAINT ORANGE (-3550 1675);
DISPLAY INVISIBLE (-3550 1675);
FORCEPROP 1 LASTPIN (-3600 1575) $PN 1
J 0
(-3590 1555);
DISPLAY 0.787234 (-3590 1555);
PAINT ORANGE (-3590 1555);
DISPLAY INVISIBLE (-3590 1555);
FORCEPROP 1 LASTPIN (-3600 1375) $PN 2
J 0
(-3590 1355);
DISPLAY 0.787234 (-3590 1355);
PAINT ORANGE (-3590 1355);
DISPLAY INVISIBLE (-3590 1355);
FORCEADD INTEL_CORP_BPAGE..1
(0 0);
FORCEPROP 1 LAST CDS_CON_LAST_MODIFIED Tue Dec 01 11:52:32 2015
J 0
(-1425 325);
PAINT ORANGE (-1425 325);
DISPLAY INVISIBLE (-1425 325);
FORCEPROP 1 LAST CUSTOM_TXT_CDS <CURRENT_DESIGN_SHEET> OF <TOTAL_DESIGN_SHEETS>
J 0
(-500 25);
PAINT GREEN (-500 25);
FORCEPROP 1 LAST CUSTOM_TXT_CDS <CON_LAST_MODIFIED>
J 0
(-1925 350);
PAINT GREEN (-1925 350);
FORCEPROP 2 LAST CUSTOM_TXT_CDS <XR_PAGE_TITLE>
J 0
(-7890 5250);
DISPLAY 0.638298 (-7890 5250);
PAINT PINK (-7890 5250);
DISPLAY INVISIBLE (-7890 5250);
FORCEPROP 1 LAST SCH_TITLE ADD DIMM CAP (2/2)
J 0
(-7950 50);
DISPLAY 2.468085 (-7950 50);
PAINT ORANGE (-7950 50);
FORCEPROP 1 LAST SCH_ADDRESS1 2200 Mission College Blvd.
J 0
(-3975 125);
DISPLAY 0.872340 (-3975 125);
PAINT GREEN (-3975 125);
FORCEPROP 1 LAST SCH_ADDRESS2 P.O. BOX 58119
J 0
(-3975 75);
DISPLAY 0.872340 (-3975 75);
PAINT GREEN (-3975 75);
FORCEPROP 1 LAST SCH_ADDRESS3 Santa Clara, CA 95052-8119
J 0
(-3975 25);
DISPLAY 0.872340 (-3975 25);
PAINT GREEN (-3975 25);
FORCEPROP 1 LAST SCH_REV 0.1
J 0
(-250 150);
DISPLAY 1.170213 (-250 150);
PAINT GREEN (-250 150);
FORCEPROP 1 LAST SCH_NUMBER 000000-000
J 0
(-1300 150);
DISPLAY 1.702128 (-1300 150);
PAINT GREEN (-1300 150);
FORCEPROP 1 LAST SCH_DEPT UNKNOWN
J 1
(-4450 100);
DISPLAY 1.255319 (-4450 100);
PAINT ORANGE (-4450 100);
FORCEPROP 2 LAST CDS_LIB mstr_symbols
J 0
(0 0);
PAINT MONO (0 0);
DISPLAY INVISIBLE (0 0);
FORCEPROP 2 LAST PAGE_BORDER TRUE
J 0
(-7890 5250);
DISPLAY 0.638298 (-7890 5250);
PAINT PINK (-7890 5250);
DISPLAY INVISIBLE (-7890 5250);
FORCEPROP 1 LAST COMMENT_BODY TRUE
J 0
(12 12);
DISPLAY 0.468085 (12 12);
PAINT GREEN (12 12);
DISPLAY INVISIBLE (12 12);
FORCEPROP 2 LAST CDS_XR_PAGE_TITLE CR-243 : @BASEBOARD_FAB2_LIB.BASEBOARD_FAB2(SCH_1):PAGE243
J 0
(-7890 5250);
DISPLAY 0.638298 (-7890 5250);
PAINT PINK (-7890 5250);
DISPLAY INVISIBLE (-7890 5250);
WIRE 16 -1 (-4650 1275)(-4650 1075);
WIRE 16 -1 (-4650 1075)(-4950 1075);
WIRE 16 -1 (-4950 1275)(-4950 1075);
WIRE 16 -1 (-4950 1075)(-5250 1075);
WIRE 16 -1 (-5250 1275)(-5250 1075);
WIRE 16 -1 (-5250 1075)(-5550 1075);
WIRE 16 -1 (-5550 1275)(-5550 1075);
WIRE 16 -1 (-5550 1075)(-5850 1075);
WIRE 16 -1 (-5850 1275)(-5850 1075);
WIRE 16 -1 (-5850 1075)(-6150 1075);
WIRE 16 -1 (-6150 1275)(-6150 1075);
WIRE 16 -1 (-6450 1075)(-6150 1075);
WIRE 16 -1 (-6450 1275)(-6450 1075);
WIRE 16 -1 (-6775 1075)(-6450 1075);
WIRE 16 -1 (-6775 1275)(-6775 1075);
WIRE 16 -1 (-7100 1075)(-6775 1075);
WIRE 16 -1 (-7100 1275)(-7100 1075);
WIRE 16 -1 (-7100 1075)(-7100 925);
WIRE 16 -1 (-6700 3325)(-6700 3550);
WIRE 16 -1 (-7125 3325)(-6700 3325);
WIRE 16 -1 (-7125 3550)(-7125 3325);
WIRE 16 -1 (-7125 3175)(-7125 3325);
WIRE 16 -1 (-6700 3750)(-6700 3925);
WIRE 16 -1 (-6700 3925)(-7125 3925);
WIRE 16 -1 (-7125 3925)(-7125 4025);
WIRE 16 -1 (-7125 3925)(-7125 3750);
WIRE 16 -1 (-1150 1375)(-1150 1175);
WIRE 16 -1 (-1150 1175)(-1450 1175);
WIRE 16 -1 (-1450 1375)(-1450 1175);
WIRE 16 -1 (-1450 1175)(-1750 1175);
WIRE 16 -1 (-1750 1375)(-1750 1175);
WIRE 16 -1 (-1750 1175)(-2050 1175);
WIRE 16 -1 (-2050 1375)(-2050 1175);
WIRE 16 -1 (-2050 1175)(-2350 1175);
WIRE 16 -1 (-2350 1375)(-2350 1175);
WIRE 16 -1 (-2350 1175)(-2650 1175);
WIRE 16 -1 (-2650 1375)(-2650 1175);
WIRE 16 -1 (-2650 1175)(-3000 1175);
WIRE 16 -1 (-3000 1375)(-3000 1175);
WIRE 16 -1 (-3000 1175)(-3300 1175);
WIRE 16 -1 (-3300 1375)(-3300 1175);
WIRE 16 -1 (-3300 1175)(-3600 1175);
WIRE 16 -1 (-3600 1375)(-3600 1175);
WIRE 16 -1 (-3600 1175)(-3600 1025);
WIRE 16 -1 (-1150 1575)(-1150 1675);
WIRE 16 -1 (-1450 1675)(-1150 1675);
WIRE 16 -1 (-1450 1575)(-1450 1675);
WIRE 16 -1 (-1450 1675)(-1750 1675);
WIRE 16 -1 (-1750 1575)(-1750 1675);
WIRE 16 -1 (-1750 1675)(-2050 1675);
WIRE 16 -1 (-2050 1575)(-2050 1675);
WIRE 16 -1 (-2350 1675)(-2050 1675);
WIRE 16 -1 (-2350 1575)(-2350 1675);
WIRE 16 -1 (-2650 1675)(-2350 1675);
WIRE 16 -1 (-2650 1575)(-2650 1675);
WIRE 16 -1 (-3000 1675)(-2650 1675);
WIRE 16 -1 (-3000 1575)(-3000 1675);
WIRE 16 -1 (-3300 1675)(-3000 1675);
WIRE 16 -1 (-3300 1575)(-3300 1675);
WIRE 16 -1 (-3600 1675)(-3300 1675);
WIRE 16 -1 (-3600 1575)(-3600 1675);
WIRE 16 -1 (-3600 1675)(-3600 1750);
WIRE 16 -1 (-4650 1475)(-4650 1575);
WIRE 16 -1 (-4950 1575)(-4650 1575);
WIRE 16 -1 (-4950 1475)(-4950 1575);
WIRE 16 -1 (-4950 1575)(-5250 1575);
WIRE 16 -1 (-5250 1475)(-5250 1575);
WIRE 16 -1 (-5250 1575)(-5550 1575);
WIRE 16 -1 (-5550 1475)(-5550 1575);
WIRE 16 -1 (-5550 1575)(-5850 1575);
WIRE 16 -1 (-5850 1475)(-5850 1575);
WIRE 16 -1 (-5850 1575)(-6150 1575);
WIRE 16 -1 (-6150 1475)(-6150 1575);
WIRE 16 -1 (-6450 1575)(-6150 1575);
WIRE 16 -1 (-6450 1475)(-6450 1575);
WIRE 16 -1 (-6775 1575)(-6450 1575);
WIRE 16 -1 (-6775 1475)(-6775 1575);
WIRE 16 -1 (-7100 1575)(-6775 1575);
WIRE 16 -1 (-7100 1475)(-7100 1575);
WIRE 16 -1 (-7100 1575)(-7100 1650);
WIRE 16 -1 (-1150 2475)(-1150 2275);
WIRE 16 -1 (-1150 2275)(-1450 2275);
WIRE 16 -1 (-1450 2475)(-1450 2275);
WIRE 16 -1 (-1450 2275)(-1750 2275);
WIRE 16 -1 (-1750 2475)(-1750 2275);
WIRE 16 -1 (-1750 2275)(-2050 2275);
WIRE 16 -1 (-2050 2475)(-2050 2275);
WIRE 16 -1 (-2050 2275)(-2350 2275);
WIRE 16 -1 (-2350 2475)(-2350 2275);
WIRE 16 -1 (-2350 2275)(-2650 2275);
WIRE 16 -1 (-2650 2475)(-2650 2275);
WIRE 16 -1 (-2650 2275)(-3000 2275);
WIRE 16 -1 (-3000 2475)(-3000 2275);
WIRE 16 -1 (-3000 2275)(-3300 2275);
WIRE 16 -1 (-3300 2475)(-3300 2275);
WIRE 16 -1 (-3300 2275)(-3600 2275);
WIRE 16 -1 (-3600 2475)(-3600 2275);
WIRE 16 -1 (-3600 2275)(-3600 2125);
WIRE 16 -1 (-1150 2675)(-1150 2775);
WIRE 16 -1 (-1450 2775)(-1150 2775);
WIRE 16 -1 (-1450 2675)(-1450 2775);
WIRE 16 -1 (-1450 2775)(-1750 2775);
WIRE 16 -1 (-1750 2675)(-1750 2775);
WIRE 16 -1 (-1750 2775)(-2050 2775);
WIRE 16 -1 (-2050 2675)(-2050 2775);
WIRE 16 -1 (-2350 2775)(-2050 2775);
WIRE 16 -1 (-2350 2675)(-2350 2775);
WIRE 16 -1 (-2650 2775)(-2350 2775);
WIRE 16 -1 (-2650 2675)(-2650 2775);
WIRE 16 -1 (-3000 2775)(-2650 2775);
WIRE 16 -1 (-3000 2675)(-3000 2775);
WIRE 16 -1 (-3300 2775)(-3000 2775);
WIRE 16 -1 (-3300 2675)(-3300 2775);
WIRE 16 -1 (-3600 2775)(-3300 2775);
WIRE 16 -1 (-3600 2675)(-3600 2775);
WIRE 16 -1 (-3600 2775)(-3600 2850);
WIRE 16 -1 (-3200 3600)(-3200 3825);
WIRE 16 -1 (-3600 3600)(-3200 3600);
WIRE 16 -1 (-3600 3825)(-3600 3600);
WIRE 16 -1 (-3600 3450)(-3600 3600);
WIRE 16 -1 (-3200 4025)(-3200 4175);
WIRE 16 -1 (-3200 4175)(-3600 4175);
WIRE 16 -1 (-3600 4300)(-3600 4175);
WIRE 16 -1 (-3600 4175)(-3600 4025);
WIRE 16 -1 (-4650 2400)(-4650 2200);
WIRE 16 -1 (-4650 2200)(-4950 2200);
WIRE 16 -1 (-4950 2400)(-4950 2200);
WIRE 16 -1 (-4950 2200)(-5250 2200);
WIRE 16 -1 (-5250 2400)(-5250 2200);
WIRE 16 -1 (-5550 2200)(-5250 2200);
WIRE 16 -1 (-5550 2400)(-5550 2200);
WIRE 16 -1 (-5550 2200)(-5850 2200);
WIRE 16 -1 (-5850 2400)(-5850 2200);
WIRE 16 -1 (-6150 2200)(-5850 2200);
WIRE 16 -1 (-6150 2400)(-6150 2200);
WIRE 16 -1 (-6500 2200)(-6150 2200);
WIRE 16 -1 (-6500 2400)(-6500 2200);
WIRE 16 -1 (-6800 2200)(-6500 2200);
WIRE 16 -1 (-6800 2400)(-6800 2200);
WIRE 16 -1 (-7125 2200)(-6800 2200);
WIRE 16 -1 (-7125 2400)(-7125 2200);
WIRE 16 -1 (-7125 2200)(-7125 2050);
WIRE 16 -1 (-4650 2600)(-4650 2700);
WIRE 16 -1 (-4950 2700)(-4650 2700);
WIRE 16 -1 (-4950 2600)(-4950 2700);
WIRE 16 -1 (-4950 2700)(-5250 2700);
WIRE 16 -1 (-5250 2600)(-5250 2700);
WIRE 16 -1 (-5550 2700)(-5250 2700);
WIRE 16 -1 (-5550 2600)(-5550 2700);
WIRE 16 -1 (-5850 2700)(-5550 2700);
WIRE 16 -1 (-5850 2600)(-5850 2700);
WIRE 16 -1 (-6150 2700)(-5850 2700);
WIRE 16 -1 (-6150 2700)(-6150 2600);
WIRE 16 -1 (-6500 2700)(-6150 2700);
WIRE 16 -1 (-6500 2600)(-6500 2700);
WIRE 16 -1 (-6800 2700)(-6500 2700);
WIRE 16 -1 (-6800 2600)(-6800 2700);
WIRE 16 -1 (-7125 2700)(-6800 2700);
WIRE 16 -1 (-7125 2600)(-7125 2700);
WIRE 16 -1 (-7125 2700)(-7125 2775);
DOT 1 (-4950 1575);
DOT 1 (-7125 2700);
DOT 1 (-5250 2200);
DOT 1 (-7125 2200);
DOT 1 (-6800 2200);
DOT 1 (-6500 2200);
DOT 1 (-6150 2200);
DOT 1 (-5850 2200);
DOT 1 (-5550 2200);
DOT 1 (-4950 2200);
DOT 1 (-6800 2700);
DOT 1 (-6500 2700);
DOT 1 (-6150 2700);
DOT 1 (-5850 2700);
DOT 1 (-5550 2700);
DOT 1 (-5250 2700);
DOT 1 (-4950 2700);
DOT 1 (-6450 1575);
DOT 1 (-6775 1575);
DOT 1 (-7125 3925);
DOT 1 (-7100 1575);
DOT 1 (-7125 3325);
DOT 1 (-3600 4175);
DOT 1 (-1450 2775);
DOT 1 (-1450 2275);
DOT 1 (-1750 2775);
DOT 1 (-2050 2775);
DOT 1 (-1750 2275);
DOT 1 (-2050 2275);
DOT 1 (-1450 1675);
DOT 1 (-1450 1175);
DOT 1 (-1750 1675);
DOT 1 (-2050 1675);
DOT 1 (-1750 1175);
DOT 1 (-2050 1175);
DOT 1 (-2350 2775);
DOT 1 (-2650 2775);
DOT 1 (-2350 2275);
DOT 1 (-2650 2275);
DOT 1 (-3000 2775);
DOT 1 (-3000 2275);
DOT 1 (-3600 3600);
DOT 1 (-3300 2775);
DOT 1 (-3600 2775);
DOT 1 (-3300 2275);
DOT 1 (-3600 2275);
DOT 1 (-2350 1675);
DOT 1 (-2650 1675);
DOT 1 (-2350 1175);
DOT 1 (-2650 1175);
DOT 1 (-3000 1675);
DOT 1 (-3000 1175);
DOT 1 (-3300 1675);
DOT 1 (-3600 1675);
DOT 1 (-3300 1175);
DOT 1 (-3600 1175);
DOT 1 (-5250 1575);
DOT 1 (-5250 1075);
DOT 1 (-5550 1575);
DOT 1 (-5550 1075);
DOT 1 (-5850 1575);
DOT 1 (-6150 1575);
DOT 1 (-5850 1075);
DOT 1 (-6150 1075);
DOT 1 (-6450 1075);
DOT 1 (-6775 1075);
DOT 1 (-7100 1075);
DOT 1 (-4950 1075);
FORCENOTE
TP FAB1 ADD CAP ON DIMM BOTTOM SIDE 1116
(-4834 692) 0;
DISPLAY LEFT (-4834 692);
DISPLAY 1.021277 (-4834 692);
PAINT RED (-4834 692);
QUIT
